(kicad_sch (version 20230121) (generator eeschema)

  (paper "A2")

  (title_block
    (title "SDI-MIPI Bridge")
    (date "2023-10-12")
    (rev "1.3.4")
    (comment 1 "www.antmicro.com")
    (comment 2 "Antmicro Ltd.")
  )

  (junction (at 69.85 243.84) (diameter 0) (color 0 0 0 0)
  )
  (junction (at 144.78 224.79) (diameter 0) (color 0 0 0 0)
  )
  (junction (at 168.91 264.16) (diameter 0) (color 0 0 0 0)
  )
  (junction (at 236.22 347.98) (diameter 0) (color 0 0 0 0)
  )
  (junction (at 274.32 226.06) (diameter 0) (color 0 0 0 0)
  )
  (junction (at 374.65 303.53) (diameter 0) (color 0 0 0 0)
  )
  (junction (at 76.2 302.26) (diameter 0) (color 0 0 0 0)
  )
  (junction (at 312.42 73.66) (diameter 0) (color 0 0 0 0)
  )
  (junction (at 386.08 326.39) (diameter 0) (color 0 0 0 0)
  )
  (junction (at 326.39 293.37) (diameter 0) (color 0 0 0 0)
  )
  (junction (at 153.67 264.16) (diameter 0) (color 0 0 0 0)
  )
  (junction (at 378.46 326.39) (diameter 0) (color 0 0 0 0)
  )
  (junction (at 146.05 152.4) (diameter 0) (color 0 0 0 0)
  )
  (junction (at 363.22 48.26) (diameter 0) (color 0 0 0 0)
  )
  (junction (at 265.43 274.32) (diameter 0) (color 0 0 0 0)
  )
  (junction (at 154.94 152.4) (diameter 0) (color 0 0 0 0)
  )
  (junction (at 312.42 63.5) (diameter 0) (color 0 0 0 0)
  )
  (junction (at 312.42 68.58) (diameter 0) (color 0 0 0 0)
  )
  (junction (at 144.78 264.16) (diameter 0) (color 0 0 0 0)
  )
  (junction (at 378.46 293.37) (diameter 0) (color 0 0 0 0)
  )
  (junction (at 370.84 85.09) (diameter 0) (color 0 0 0 0)
  )
  (junction (at 78.74 228.6) (diameter 0) (color 0 0 0 0)
  )
  (junction (at 237.49 226.06) (diameter 0) (color 0 0 0 0)
  )
  (junction (at 337.82 311.15) (diameter 0) (color 0 0 0 0)
  )
  (junction (at 330.2 293.37) (diameter 0) (color 0 0 0 0)
  )
  (junction (at 377.19 35.56) (diameter 0) (color 0 0 0 0)
  )
  (junction (at 34.29 302.26) (diameter 0) (color 0 0 0 0)
  )
  (junction (at 168.91 234.95) (diameter 0) (color 0 0 0 0)
  )
  (junction (at 381 113.03) (diameter 0) (color 0 0 0 0)
  )
  (junction (at 152.4 303.53) (diameter 0) (color 0 0 0 0)
  )
  (junction (at 389.89 313.69) (diameter 0) (color 0 0 0 0)
  )
  (junction (at 83.82 302.26) (diameter 0) (color 0 0 0 0)
  )
  (junction (at 508 64.77) (diameter 0) (color 0 0 0 0)
  )
  (junction (at 389.89 293.37) (diameter 0) (color 0 0 0 0)
  )
  (junction (at 378.46 306.07) (diameter 0) (color 0 0 0 0)
  )
  (junction (at 377.19 48.26) (diameter 0) (color 0 0 0 0)
  )
  (junction (at 280.67 66.04) (diameter 0) (color 0 0 0 0)
  )
  (junction (at 444.5 69.85) (diameter 0) (color 0 0 0 0)
  )
  (junction (at 259.08 140.97) (diameter 0) (color 0 0 0 0)
  )
  (junction (at 538.48 325.12) (diameter 0) (color 0 0 0 0)
  )
  (junction (at 334.01 326.39) (diameter 0) (color 0 0 0 0)
  )
  (junction (at 382.27 308.61) (diameter 0) (color 0 0 0 0)
  )
  (junction (at 168.91 224.79) (diameter 0) (color 0 0 0 0)
  )
  (junction (at 238.76 299.72) (diameter 0) (color 0 0 0 0)
  )
  (junction (at 228.6 339.09) (diameter 0) (color 0 0 0 0)
  )
  (junction (at 312.42 60.96) (diameter 0) (color 0 0 0 0)
  )
  (junction (at 175.26 303.53) (diameter 0) (color 0 0 0 0)
  )
  (junction (at 78.74 237.49) (diameter 0) (color 0 0 0 0)
  )
  (junction (at 251.46 339.09) (diameter 0) (color 0 0 0 0)
  )
  (junction (at 444.5 77.47) (diameter 0) (color 0 0 0 0)
  )
  (junction (at 168.91 160.02) (diameter 0) (color 0 0 0 0)
  )
  (junction (at 49.53 302.26) (diameter 0) (color 0 0 0 0)
  )
  (junction (at 83.82 328.93) (diameter 0) (color 0 0 0 0)
  )
  (junction (at 36.83 228.6) (diameter 0) (color 0 0 0 0)
  )
  (junction (at 144.78 234.95) (diameter 0) (color 0 0 0 0)
  )
  (junction (at 453.39 130.81) (diameter 0) (color 0 0 0 0)
  )
  (junction (at 360.68 369.57) (diameter 0) (color 0 0 0 0)
  )
  (junction (at 458.47 151.13) (diameter 0) (color 0 0 0 0)
  )
  (junction (at 41.91 302.26) (diameter 0) (color 0 0 0 0)
  )
  (junction (at 176.53 160.02) (diameter 0) (color 0 0 0 0)
  )
  (junction (at 154.94 144.78) (diameter 0) (color 0 0 0 0)
  )
  (junction (at 49.53 228.6) (diameter 0) (color 0 0 0 0)
  )
  (junction (at 261.62 378.46) (diameter 0) (color 0 0 0 0)
  )
  (junction (at 381 80.01) (diameter 0) (color 0 0 0 0)
  )
  (junction (at 508 62.23) (diameter 0) (color 0 0 0 0)
  )
  (junction (at 280.67 63.5) (diameter 0) (color 0 0 0 0)
  )
  (junction (at 146.05 144.78) (diameter 0) (color 0 0 0 0)
  )
  (junction (at 334.645 149.86) (diameter 0) (color 0 0 0 0)
  )
  (junction (at 326.39 326.39) (diameter 0) (color 0 0 0 0)
  )
  (junction (at 337.82 326.39) (diameter 0) (color 0 0 0 0)
  )
  (junction (at 537.21 153.67) (diameter 0) (color 0 0 0 0)
  )
  (junction (at 153.67 234.95) (diameter 0) (color 0 0 0 0)
  )
  (junction (at 382.27 293.37) (diameter 0) (color 0 0 0 0)
  )
  (junction (at 330.2 326.39) (diameter 0) (color 0 0 0 0)
  )
  (junction (at 326.39 303.53) (diameter 0) (color 0 0 0 0)
  )
  (junction (at 341.63 326.39) (diameter 0) (color 0 0 0 0)
  )
  (junction (at 543.56 153.67) (diameter 0) (color 0 0 0 0)
  )
  (junction (at 538.48 287.02) (diameter 0) (color 0 0 0 0)
  )
  (junction (at 386.08 293.37) (diameter 0) (color 0 0 0 0)
  )
  (junction (at 110.49 162.56) (diameter 0) (color 0 0 0 0)
  )
  (junction (at 246.38 266.7) (diameter 0) (color 0 0 0 0)
  )
  (junction (at 76.2 328.93) (diameter 0) (color 0 0 0 0)
  )
  (junction (at 87.63 228.6) (diameter 0) (color 0 0 0 0)
  )
  (junction (at 444.5 100.33) (diameter 0) (color 0 0 0 0)
  )
  (junction (at 246.38 226.06) (diameter 0) (color 0 0 0 0)
  )
  (junction (at 444.5 160.655) (diameter 0) (color 0 0 0 0)
  )
  (junction (at 228.6 266.7) (diameter 0) (color 0 0 0 0)
  )
  (junction (at 345.44 316.23) (diameter 0) (color 0 0 0 0)
  )
  (junction (at 386.08 311.15) (diameter 0) (color 0 0 0 0)
  )
  (junction (at 49.53 328.93) (diameter 0) (color 0 0 0 0)
  )
  (junction (at 167.64 303.53) (diameter 0) (color 0 0 0 0)
  )
  (junction (at 90.17 133.35) (diameter 0) (color 0 0 0 0)
  )
  (junction (at 265.43 226.06) (diameter 0) (color 0 0 0 0)
  )
  (junction (at 427.99 151.13) (diameter 0) (color 0 0 0 0)
  )
  (junction (at 110.49 165.1) (diameter 0) (color 0 0 0 0)
  )
  (junction (at 228.6 226.06) (diameter 0) (color 0 0 0 0)
  )
  (junction (at 271.78 226.06) (diameter 0) (color 0 0 0 0)
  )
  (junction (at 165.1 349.25) (diameter 0) (color 0 0 0 0)
  )
  (junction (at 337.82 293.37) (diameter 0) (color 0 0 0 0)
  )
  (junction (at 444.5 107.95) (diameter 0) (color 0 0 0 0)
  )
  (junction (at 177.8 234.95) (diameter 0) (color 0 0 0 0)
  )
  (junction (at 506.73 41.91) (diameter 0) (color 0 0 0 0)
  )
  (junction (at 530.86 153.67) (diameter 0) (color 0 0 0 0)
  )
  (junction (at 334.01 308.61) (diameter 0) (color 0 0 0 0)
  )
  (junction (at 250.19 299.72) (diameter 0) (color 0 0 0 0)
  )
  (junction (at 237.49 266.7) (diameter 0) (color 0 0 0 0)
  )
  (junction (at 373.38 163.83) (diameter 0) (color 0 0 0 0)
  )
  (junction (at 162.56 152.4) (diameter 0) (color 0 0 0 0)
  )
  (junction (at 444.5 62.23) (diameter 0) (color 0 0 0 0)
  )
  (junction (at 538.48 322.58) (diameter 0) (color 0 0 0 0)
  )
  (junction (at 176.53 264.16) (diameter 0) (color 0 0 0 0)
  )
  (junction (at 69.85 246.38) (diameter 0) (color 0 0 0 0)
  )
  (junction (at 341.63 313.69) (diameter 0) (color 0 0 0 0)
  )
  (junction (at 248.92 140.97) (diameter 0) (color 0 0 0 0)
  )
  (junction (at 256.54 226.06) (diameter 0) (color 0 0 0 0)
  )
  (junction (at 450.85 133.35) (diameter 0) (color 0 0 0 0)
  )
  (junction (at 312.42 66.04) (diameter 0) (color 0 0 0 0)
  )
  (junction (at 393.7 316.23) (diameter 0) (color 0 0 0 0)
  )
  (junction (at 538.48 284.48) (diameter 0) (color 0 0 0 0)
  )
  (junction (at 153.67 224.79) (diameter 0) (color 0 0 0 0)
  )
  (junction (at 34.29 328.93) (diameter 0) (color 0 0 0 0)
  )
  (junction (at 177.8 224.79) (diameter 0) (color 0 0 0 0)
  )
  (junction (at 236.22 339.09) (diameter 0) (color 0 0 0 0)
  )
  (junction (at 334.01 293.37) (diameter 0) (color 0 0 0 0)
  )
  (junction (at 450.85 241.3) (diameter 0) (color 0 0 0 0)
  )
  (junction (at 69.85 228.6) (diameter 0) (color 0 0 0 0)
  )
  (junction (at 99.06 133.35) (diameter 0) (color 0 0 0 0)
  )
  (junction (at 271.78 266.7) (diameter 0) (color 0 0 0 0)
  )
  (junction (at 278.765 372.11) (diameter 0) (color 0 0 0 0)
  )
  (junction (at 374.65 293.37) (diameter 0) (color 0 0 0 0)
  )
  (junction (at 337.82 203.2) (diameter 0) (color 0 0 0 0)
  )
  (junction (at 228.6 299.72) (diameter 0) (color 0 0 0 0)
  )
  (junction (at 325.12 149.86) (diameter 0) (color 0 0 0 0)
  )
  (junction (at 417.83 241.3) (diameter 0) (color 0 0 0 0)
  )
  (junction (at 265.43 266.7) (diameter 0) (color 0 0 0 0)
  )
  (junction (at 389.89 326.39) (diameter 0) (color 0 0 0 0)
  )
  (junction (at 370.84 88.9) (diameter 0) (color 0 0 0 0)
  )
  (junction (at 278.765 378.46) (diameter 0) (color 0 0 0 0)
  )
  (junction (at 144.78 303.53) (diameter 0) (color 0 0 0 0)
  )
  (junction (at 341.63 293.37) (diameter 0) (color 0 0 0 0)
  )
  (junction (at 330.2 306.07) (diameter 0) (color 0 0 0 0)
  )
  (junction (at 374.65 326.39) (diameter 0) (color 0 0 0 0)
  )
  (junction (at 360.68 384.81) (diameter 0) (color 0 0 0 0)
  )
  (junction (at 41.91 328.93) (diameter 0) (color 0 0 0 0)
  )
  (junction (at 417.83 243.84) (diameter 0) (color 0 0 0 0)
  )
  (junction (at 256.54 266.7) (diameter 0) (color 0 0 0 0)
  )
  (junction (at 382.27 326.39) (diameter 0) (color 0 0 0 0)
  )

  (no_connect (at 461.01 143.51))
  (no_connect (at 520.7 49.53))
  (no_connect (at 461.01 146.05))
  (no_connect (at 44.45 124.46))
  (no_connect (at 461.01 74.93))
  (no_connect (at 548.64 64.77))
  (no_connect (at 461.01 110.49))
  (no_connect (at 461.01 72.39))
  (no_connect (at 461.01 118.11))
  (no_connect (at 461.01 64.77))
  (no_connect (at 461.01 140.97))
  (no_connect (at 448.31 115.57))
  (no_connect (at 461.01 67.31))
  (no_connect (at 461.01 123.19))
  (no_connect (at 461.01 113.03))
  (no_connect (at 461.01 128.27))
  (no_connect (at 461.01 148.59))
  (no_connect (at 461.01 156.21))
  (no_connect (at 548.64 59.69))
  (no_connect (at 461.01 125.73))
  (no_connect (at 461.01 120.65))
  (no_connect (at 461.01 158.75))

  (bus_entry (at 120.65 80.01) (size 2.54 -2.54)
    (stroke (width 0) (type default))
  )
  (bus_entry (at 120.65 90.17) (size 2.54 -2.54)
    (stroke (width 0) (type default))
  )
  (bus_entry (at 120.65 92.71) (size 2.54 -2.54)
    (stroke (width 0) (type default))
  )
  (bus_entry (at 434.34 281.94) (size -2.54 -2.54)
    (stroke (width 0) (type default))
  )
  (bus_entry (at 434.34 279.4) (size -2.54 -2.54)
    (stroke (width 0) (type default))
  )
  (bus_entry (at 120.65 72.39) (size 2.54 -2.54)
    (stroke (width 0) (type default))
  )
  (bus_entry (at 120.65 87.63) (size 2.54 -2.54)
    (stroke (width 0) (type default))
  )
  (bus_entry (at 434.34 294.64) (size -2.54 -2.54)
    (stroke (width 0) (type default))
  )
  (bus_entry (at 434.34 289.56) (size -2.54 -2.54)
    (stroke (width 0) (type default))
  )
  (bus_entry (at 434.34 297.18) (size -2.54 -2.54)
    (stroke (width 0) (type default))
  )
  (bus_entry (at 120.65 82.55) (size 2.54 -2.54)
    (stroke (width 0) (type default))
  )
  (bus_entry (at 434.34 266.7) (size -2.54 -2.54)
    (stroke (width 0) (type default))
  )
  (bus_entry (at 434.34 292.1) (size -2.54 -2.54)
    (stroke (width 0) (type default))
  )
  (bus_entry (at 120.65 85.09) (size 2.54 -2.54)
    (stroke (width 0) (type default))
  )
  (bus_entry (at 434.34 284.48) (size -2.54 -2.54)
    (stroke (width 0) (type default))
  )
  (bus_entry (at 434.34 287.02) (size -2.54 -2.54)
    (stroke (width 0) (type default))
  )
  (bus_entry (at 120.65 69.85) (size 2.54 -2.54)
    (stroke (width 0) (type default))
  )
  (bus_entry (at 120.65 74.93) (size 2.54 -2.54)
    (stroke (width 0) (type default))
  )
  (bus_entry (at 120.65 77.47) (size 2.54 -2.54)
    (stroke (width 0) (type default))
  )
  (bus_entry (at 434.34 299.72) (size -2.54 -2.54)
    (stroke (width 0) (type default))
  )

  (wire (pts (xy 382.27 308.61) (xy 382.27 317.5))
    (stroke (width 0) (type default))
  )
  (wire (pts (xy 355.6 316.23) (xy 393.7 316.23))
    (stroke (width 0) (type default))
  )
  (wire (pts (xy 337.82 326.39) (xy 341.63 326.39))
    (stroke (width 0) (type default))
  )
  (wire (pts (xy 377.19 45.72) (xy 377.19 48.26))
    (stroke (width 0) (type default))
  )
  (wire (pts (xy 537.21 153.67) (xy 543.56 153.67))
    (stroke (width 0) (type default))
  )
  (wire (pts (xy 374.65 35.56) (xy 377.19 35.56))
    (stroke (width 0) (type default))
  )
  (wire (pts (xy 210.82 78.74) (xy 227.33 78.74))
    (stroke (width 0) (type default))
  )
  (wire (pts (xy 337.82 215.9) (xy 326.39 215.9))
    (stroke (width 0) (type default))
  )
  (wire (pts (xy 210.82 86.36) (xy 227.33 86.36))
    (stroke (width 0) (type default))
  )
  (wire (pts (xy 382.27 293.37) (xy 386.08 293.37))
    (stroke (width 0) (type default))
  )
  (bus (pts (xy 123.19 77.47) (xy 123.19 80.01))
    (stroke (width 0) (type default))
  )

  (wire (pts (xy 355.6 308.61) (xy 382.27 308.61))
    (stroke (width 0) (type default))
  )
  (wire (pts (xy 165.1 349.25) (xy 165.1 350.52))
    (stroke (width 0) (type default))
  )
  (wire (pts (xy 83.82 302.26) (xy 76.2 302.26))
    (stroke (width 0) (type default))
  )
  (wire (pts (xy 461.01 77.47) (xy 444.5 77.47))
    (stroke (width 0) (type default))
  )
  (wire (pts (xy 415.29 130.81) (xy 434.34 130.81))
    (stroke (width 0) (type default))
  )
  (wire (pts (xy 434.34 287.02) (xy 459.74 287.02))
    (stroke (width 0) (type default))
  )
  (wire (pts (xy 547.37 322.58) (xy 552.45 322.58))
    (stroke (width 0) (type default))
  )
  (wire (pts (xy 95.25 157.48) (xy 95.25 158.75))
    (stroke (width 0) (type default))
  )
  (wire (pts (xy 187.96 221.615) (xy 187.96 224.79))
    (stroke (width 0) (type default))
  )
  (wire (pts (xy 523.24 287.02) (xy 538.48 287.02))
    (stroke (width 0) (type default))
  )
  (wire (pts (xy 542.29 110.49) (xy 567.69 110.49))
    (stroke (width 0) (type default))
  )
  (polyline (pts (xy 299.72 107.95) (xy 299.72 407.67))
    (stroke (width 0) (type default))
  )

  (wire (pts (xy 99.06 133.35) (xy 99.06 134.62))
    (stroke (width 0) (type default))
  )
  (wire (pts (xy 326.39 299.72) (xy 326.39 303.53))
    (stroke (width 0) (type default))
  )
  (wire (pts (xy 355.6 306.07) (xy 378.46 306.07))
    (stroke (width 0) (type default))
  )
  (wire (pts (xy 41.91 328.93) (xy 34.29 328.93))
    (stroke (width 0) (type default))
  )
  (wire (pts (xy 381 72.39) (xy 381 71.12))
    (stroke (width 0) (type default))
  )
  (polyline (pts (xy 64.77 140.97) (xy 11.43 140.97))
    (stroke (width 0) (type default))
  )

  (wire (pts (xy 57.15 302.26) (xy 49.53 302.26))
    (stroke (width 0) (type default))
  )
  (wire (pts (xy 265.43 266.7) (xy 271.78 266.7))
    (stroke (width 0) (type default))
  )
  (wire (pts (xy 83.82 332.74) (xy 83.82 328.93))
    (stroke (width 0) (type default))
  )
  (wire (pts (xy 523.24 322.58) (xy 538.48 322.58))
    (stroke (width 0) (type default))
  )
  (wire (pts (xy 523.24 276.86) (xy 566.42 276.86))
    (stroke (width 0) (type default))
  )
  (wire (pts (xy 434.34 297.18) (xy 459.74 297.18))
    (stroke (width 0) (type default))
  )
  (wire (pts (xy 378.46 88.9) (xy 391.16 88.9))
    (stroke (width 0) (type default))
  )
  (wire (pts (xy 110.49 162.56) (xy 111.76 162.56))
    (stroke (width 0) (type default))
  )
  (wire (pts (xy 337.82 203.2) (xy 337.82 207.01))
    (stroke (width 0) (type default))
  )
  (wire (pts (xy 548.64 62.23) (xy 565.15 62.23))
    (stroke (width 0) (type default))
  )
  (wire (pts (xy 176.53 63.5) (xy 179.07 63.5))
    (stroke (width 0) (type default))
  )
  (wire (pts (xy 237.49 267.97) (xy 237.49 266.7))
    (stroke (width 0) (type default))
  )
  (wire (pts (xy 370.84 90.17) (xy 370.84 88.9))
    (stroke (width 0) (type default))
  )
  (wire (pts (xy 434.34 330.2) (xy 459.74 330.2))
    (stroke (width 0) (type default))
  )
  (wire (pts (xy 393.7 322.58) (xy 393.7 326.39))
    (stroke (width 0) (type default))
  )
  (wire (pts (xy 57.15 69.85) (xy 63.5 69.85))
    (stroke (width 0) (type default))
  )
  (wire (pts (xy 433.07 248.92) (xy 459.74 248.92))
    (stroke (width 0) (type default))
  )
  (wire (pts (xy 326.39 326.39) (xy 320.04 326.39))
    (stroke (width 0) (type default))
  )
  (wire (pts (xy 330.2 326.39) (xy 334.01 326.39))
    (stroke (width 0) (type default))
  )
  (wire (pts (xy 519.43 67.31) (xy 519.43 68.58))
    (stroke (width 0) (type default))
  )
  (wire (pts (xy 312.42 63.5) (xy 312.42 60.96))
    (stroke (width 0) (type default))
  )
  (wire (pts (xy 337.82 311.15) (xy 337.82 317.5))
    (stroke (width 0) (type default))
  )
  (wire (pts (xy 228.6 339.09) (xy 228.6 340.36))
    (stroke (width 0) (type default))
  )
  (wire (pts (xy 374.65 322.58) (xy 374.65 326.39))
    (stroke (width 0) (type default))
  )
  (wire (pts (xy 547.37 284.48) (xy 552.45 284.48))
    (stroke (width 0) (type default))
  )
  (wire (pts (xy 274.32 226.06) (xy 274.32 228.6))
    (stroke (width 0) (type default))
  )
  (wire (pts (xy 363.22 384.81) (xy 363.22 383.54))
    (stroke (width 0) (type default))
  )
  (wire (pts (xy 63.5 55.88) (xy 38.1 55.88))
    (stroke (width 0) (type default))
  )
  (wire (pts (xy 228.6 274.32) (xy 228.6 273.05))
    (stroke (width 0) (type default))
  )
  (wire (pts (xy 49.53 228.6) (xy 52.07 228.6))
    (stroke (width 0) (type default))
  )
  (wire (pts (xy 381 80.01) (xy 391.16 80.01))
    (stroke (width 0) (type default))
  )
  (wire (pts (xy 146.05 165.1) (xy 146.05 166.37))
    (stroke (width 0) (type default))
  )
  (wire (pts (xy 278.765 372.11) (xy 293.37 372.11))
    (stroke (width 0) (type default))
  )
  (wire (pts (xy 69.85 247.65) (xy 69.85 246.38))
    (stroke (width 0) (type default))
  )
  (polyline (pts (xy 354.33 30.48) (xy 354.33 189.23))
    (stroke (width 0) (type default))
  )

  (wire (pts (xy 532.13 105.41) (xy 506.73 105.41))
    (stroke (width 0) (type default))
  )
  (wire (pts (xy 441.96 226.06) (xy 441.96 229.87))
    (stroke (width 0) (type default))
  )
  (wire (pts (xy 278.765 378.46) (xy 293.37 378.46))
    (stroke (width 0) (type default))
  )
  (wire (pts (xy 307.34 308.61) (xy 334.01 308.61))
    (stroke (width 0) (type default))
  )
  (wire (pts (xy 52.07 233.68) (xy 49.53 233.68))
    (stroke (width 0) (type default))
  )
  (wire (pts (xy 461.01 82.55) (xy 448.31 82.55))
    (stroke (width 0) (type default))
  )
  (wire (pts (xy 43.18 160.02) (xy 35.56 160.02))
    (stroke (width 0) (type default))
  )
  (wire (pts (xy 434.34 292.1) (xy 459.74 292.1))
    (stroke (width 0) (type default))
  )
  (wire (pts (xy 334.01 308.61) (xy 334.01 317.5))
    (stroke (width 0) (type default))
  )
  (wire (pts (xy 461.01 34.29) (xy 448.31 34.29))
    (stroke (width 0) (type default))
  )
  (wire (pts (xy 245.11 140.97) (xy 248.92 140.97))
    (stroke (width 0) (type default))
  )
  (wire (pts (xy 41.91 304.8) (xy 41.91 302.26))
    (stroke (width 0) (type default))
  )
  (wire (pts (xy 152.4 152.4) (xy 154.94 152.4))
    (stroke (width 0) (type default))
  )
  (wire (pts (xy 184.15 137.16) (xy 184.15 138.43))
    (stroke (width 0) (type default))
  )
  (wire (pts (xy 389.89 299.72) (xy 389.89 313.69))
    (stroke (width 0) (type default))
  )
  (wire (pts (xy 382.27 326.39) (xy 386.08 326.39))
    (stroke (width 0) (type default))
  )
  (wire (pts (xy 179.07 82.55) (xy 161.29 82.55))
    (stroke (width 0) (type default))
  )
  (wire (pts (xy 31.75 328.93) (xy 34.29 328.93))
    (stroke (width 0) (type default))
  )
  (wire (pts (xy 461.01 102.87) (xy 448.31 102.87))
    (stroke (width 0) (type default))
  )
  (wire (pts (xy 386.08 293.37) (xy 389.89 293.37))
    (stroke (width 0) (type default))
  )
  (wire (pts (xy 144.78 303.53) (xy 144.78 306.07))
    (stroke (width 0) (type default))
  )
  (wire (pts (xy 373.38 152.4) (xy 375.92 152.4))
    (stroke (width 0) (type default))
  )
  (wire (pts (xy 49.53 328.93) (xy 41.91 328.93))
    (stroke (width 0) (type default))
  )
  (wire (pts (xy 228.6 299.72) (xy 228.6 300.99))
    (stroke (width 0) (type default))
  )
  (wire (pts (xy 378.46 326.39) (xy 382.27 326.39))
    (stroke (width 0) (type default))
  )
  (wire (pts (xy 345.44 293.37) (xy 345.44 294.64))
    (stroke (width 0) (type default))
  )
  (wire (pts (xy 246.38 226.06) (xy 256.54 226.06))
    (stroke (width 0) (type default))
  )
  (wire (pts (xy 450.85 226.06) (xy 450.85 229.87))
    (stroke (width 0) (type default))
  )
  (wire (pts (xy 233.68 372.11) (xy 240.03 372.11))
    (stroke (width 0) (type default))
  )
  (wire (pts (xy 176.53 160.02) (xy 177.8 160.02))
    (stroke (width 0) (type default))
  )
  (wire (pts (xy 220.98 372.11) (xy 228.6 372.11))
    (stroke (width 0) (type default))
  )
  (wire (pts (xy 326.39 322.58) (xy 326.39 326.39))
    (stroke (width 0) (type default))
  )
  (wire (pts (xy 326.39 326.39) (xy 330.2 326.39))
    (stroke (width 0) (type default))
  )
  (wire (pts (xy 461.01 52.07) (xy 448.31 52.07))
    (stroke (width 0) (type default))
  )
  (wire (pts (xy 106.68 143.51) (xy 106.68 133.35))
    (stroke (width 0) (type default))
  )
  (wire (pts (xy 374.65 326.39) (xy 368.3 326.39))
    (stroke (width 0) (type default))
  )
  (wire (pts (xy 372.11 236.22) (xy 372.11 238.76))
    (stroke (width 0) (type default))
  )
  (wire (pts (xy 91.44 328.93) (xy 83.82 328.93))
    (stroke (width 0) (type default))
  )
  (wire (pts (xy 36.83 228.6) (xy 36.83 229.87))
    (stroke (width 0) (type default))
  )
  (wire (pts (xy 187.96 224.79) (xy 177.8 224.79))
    (stroke (width 0) (type default))
  )
  (wire (pts (xy 450.85 234.95) (xy 450.85 241.3))
    (stroke (width 0) (type default))
  )
  (wire (pts (xy 542.29 100.33) (xy 567.69 100.33))
    (stroke (width 0) (type default))
  )
  (polyline (pts (xy 485.14 16.51) (xy 485.14 189.23))
    (stroke (width 0) (type default))
  )

  (wire (pts (xy 162.56 144.78) (xy 162.56 152.4))
    (stroke (width 0) (type default))
  )
  (wire (pts (xy 271.78 224.79) (xy 271.78 226.06))
    (stroke (width 0) (type default))
  )
  (wire (pts (xy 537.21 165.1) (xy 557.53 165.1))
    (stroke (width 0) (type default))
  )
  (wire (pts (xy 538.48 325.12) (xy 538.48 322.58))
    (stroke (width 0) (type default))
  )
  (wire (pts (xy 210.82 48.26) (xy 227.33 48.26))
    (stroke (width 0) (type default))
  )
  (wire (pts (xy 63.5 60.96) (xy 38.1 60.96))
    (stroke (width 0) (type default))
  )
  (wire (pts (xy 90.17 80.01) (xy 120.65 80.01))
    (stroke (width 0) (type default))
  )
  (wire (pts (xy 328.93 251.46) (xy 341.63 251.46))
    (stroke (width 0) (type default))
  )
  (wire (pts (xy 167.64 303.53) (xy 167.64 306.07))
    (stroke (width 0) (type default))
  )
  (wire (pts (xy 69.85 228.6) (xy 78.74 228.6))
    (stroke (width 0) (type default))
  )
  (wire (pts (xy 139.7 166.37) (xy 137.16 166.37))
    (stroke (width 0) (type default))
  )
  (wire (pts (xy 144.78 303.53) (xy 152.4 303.53))
    (stroke (width 0) (type default))
  )
  (bus (pts (xy 431.8 292.1) (xy 431.8 294.64))
    (stroke (width 0) (type default))
  )

  (wire (pts (xy 162.56 303.53) (xy 167.64 303.53))
    (stroke (width 0) (type default))
  )
  (wire (pts (xy 434.34 294.64) (xy 459.74 294.64))
    (stroke (width 0) (type default))
  )
  (wire (pts (xy 374.65 48.26) (xy 377.19 48.26))
    (stroke (width 0) (type default))
  )
  (wire (pts (xy 360.68 369.57) (xy 363.22 369.57))
    (stroke (width 0) (type default))
  )
  (wire (pts (xy 144.78 166.37) (xy 146.05 166.37))
    (stroke (width 0) (type default))
  )
  (wire (pts (xy 523.24 302.26) (xy 566.42 302.26))
    (stroke (width 0) (type default))
  )
  (wire (pts (xy 153.67 224.79) (xy 144.78 224.79))
    (stroke (width 0) (type default))
  )
  (wire (pts (xy 90.17 82.55) (xy 120.65 82.55))
    (stroke (width 0) (type default))
  )
  (wire (pts (xy 341.63 203.2) (xy 337.82 203.2))
    (stroke (width 0) (type default))
  )
  (wire (pts (xy 312.42 60.96) (xy 309.88 60.96))
    (stroke (width 0) (type default))
  )
  (wire (pts (xy 210.82 55.88) (xy 227.33 55.88))
    (stroke (width 0) (type default))
  )
  (wire (pts (xy 523.24 246.38) (xy 534.67 246.38))
    (stroke (width 0) (type default))
  )
  (wire (pts (xy 309.88 58.42) (xy 312.42 58.42))
    (stroke (width 0) (type default))
  )
  (wire (pts (xy 251.46 330.835) (xy 251.46 339.09))
    (stroke (width 0) (type default))
  )
  (wire (pts (xy 325.12 140.97) (xy 325.12 142.24))
    (stroke (width 0) (type default))
  )
  (wire (pts (xy 369.57 113.03) (xy 372.11 113.03))
    (stroke (width 0) (type default))
  )
  (wire (pts (xy 334.01 326.39) (xy 337.82 326.39))
    (stroke (width 0) (type default))
  )
  (wire (pts (xy 365.76 293.37) (xy 374.65 293.37))
    (stroke (width 0) (type default))
  )
  (wire (pts (xy 90.17 133.35) (xy 90.17 134.62))
    (stroke (width 0) (type default))
  )
  (wire (pts (xy 419.1 148.59) (xy 419.1 151.13))
    (stroke (width 0) (type default))
  )
  (wire (pts (xy 386.08 326.39) (xy 389.89 326.39))
    (stroke (width 0) (type default))
  )
  (wire (pts (xy 271.78 265.43) (xy 271.78 266.7))
    (stroke (width 0) (type default))
  )
  (wire (pts (xy 154.94 346.71) (xy 154.94 349.25))
    (stroke (width 0) (type default))
  )
  (wire (pts (xy 361.95 236.22) (xy 372.11 236.22))
    (stroke (width 0) (type default))
  )
  (wire (pts (xy 369.57 48.26) (xy 363.22 48.26))
    (stroke (width 0) (type default))
  )
  (polyline (pts (xy 443.23 128.27) (xy 443.23 118.11))
    (stroke (width 0) (type dash_dot))
  )

  (wire (pts (xy 57.15 304.8) (xy 57.15 302.26))
    (stroke (width 0) (type default))
  )
  (wire (pts (xy 259.08 154.94) (xy 259.08 157.48))
    (stroke (width 0) (type default))
  )
  (wire (pts (xy 67.31 237.49) (xy 78.74 237.49))
    (stroke (width 0) (type default))
  )
  (wire (pts (xy 370.84 80.01) (xy 370.84 85.09))
    (stroke (width 0) (type default))
  )
  (polyline (pts (xy 500.38 154.94) (xy 500.38 162.56))
    (stroke (width 0) (type default))
  )

  (wire (pts (xy 210.82 71.12) (xy 227.33 71.12))
    (stroke (width 0) (type default))
  )
  (wire (pts (xy 187.96 236.22) (xy 187.96 234.95))
    (stroke (width 0) (type default))
  )
  (wire (pts (xy 307.34 306.07) (xy 330.2 306.07))
    (stroke (width 0) (type default))
  )
  (wire (pts (xy 90.17 72.39) (xy 120.65 72.39))
    (stroke (width 0) (type default))
  )
  (wire (pts (xy 459.74 342.9) (xy 434.34 342.9))
    (stroke (width 0) (type default))
  )
  (wire (pts (xy 508 59.69) (xy 508 62.23))
    (stroke (width 0) (type default))
  )
  (wire (pts (xy 461.01 153.67) (xy 458.47 153.67))
    (stroke (width 0) (type default))
  )
  (wire (pts (xy 523.24 307.34) (xy 566.42 307.34))
    (stroke (width 0) (type default))
  )
  (polyline (pts (xy 115.57 392.43) (xy 115.57 204.47))
    (stroke (width 0) (type default))
  )

  (wire (pts (xy 459.74 162.56) (xy 459.74 161.29))
    (stroke (width 0) (type default))
  )
  (wire (pts (xy 236.22 347.98) (xy 228.6 347.98))
    (stroke (width 0) (type default))
  )
  (wire (pts (xy 152.4 303.53) (xy 157.48 303.53))
    (stroke (width 0) (type default))
  )
  (wire (pts (xy 240.03 379.73) (xy 240.03 382.27))
    (stroke (width 0) (type default))
  )
  (wire (pts (xy 256.54 228.6) (xy 256.54 226.06))
    (stroke (width 0) (type default))
  )
  (wire (pts (xy 455.93 256.54) (xy 459.74 256.54))
    (stroke (width 0) (type default))
  )
  (wire (pts (xy 548.64 57.15) (xy 565.15 57.15))
    (stroke (width 0) (type default))
  )
  (wire (pts (xy 238.76 300.99) (xy 238.76 299.72))
    (stroke (width 0) (type default))
  )
  (polyline (pts (xy 407.67 407.67) (xy 407.67 189.23))
    (stroke (width 0) (type default))
  )

  (wire (pts (xy 76.2 332.74) (xy 76.2 328.93))
    (stroke (width 0) (type default))
  )
  (wire (pts (xy 337.82 294.64) (xy 337.82 293.37))
    (stroke (width 0) (type default))
  )
  (wire (pts (xy 355.6 313.69) (xy 389.89 313.69))
    (stroke (width 0) (type default))
  )
  (wire (pts (xy 265.43 228.6) (xy 265.43 226.06))
    (stroke (width 0) (type default))
  )
  (wire (pts (xy 523.24 325.12) (xy 538.48 325.12))
    (stroke (width 0) (type default))
  )
  (wire (pts (xy 341.63 322.58) (xy 341.63 326.39))
    (stroke (width 0) (type default))
  )
  (wire (pts (xy 378.46 299.72) (xy 378.46 306.07))
    (stroke (width 0) (type default))
  )
  (wire (pts (xy 532.13 107.95) (xy 506.73 107.95))
    (stroke (width 0) (type default))
  )
  (wire (pts (xy 341.63 299.72) (xy 341.63 313.69))
    (stroke (width 0) (type default))
  )
  (wire (pts (xy 453.39 130.81) (xy 461.01 130.81))
    (stroke (width 0) (type default))
  )
  (wire (pts (xy 459.74 325.12) (xy 434.34 325.12))
    (stroke (width 0) (type default))
  )
  (wire (pts (xy 228.6 339.09) (xy 236.22 339.09))
    (stroke (width 0) (type default))
  )
  (wire (pts (xy 523.24 266.7) (xy 566.42 266.7))
    (stroke (width 0) (type default))
  )
  (wire (pts (xy 269.24 59.69) (xy 269.24 60.96))
    (stroke (width 0) (type default))
  )
  (wire (pts (xy 63.5 50.8) (xy 38.1 50.8))
    (stroke (width 0) (type default))
  )
  (wire (pts (xy 317.5 293.37) (xy 326.39 293.37))
    (stroke (width 0) (type default))
  )
  (wire (pts (xy 417.83 254) (xy 417.83 243.84))
    (stroke (width 0) (type default))
  )
  (bus (pts (xy 123.19 85.09) (xy 123.19 87.63))
    (stroke (width 0) (type default))
  )

  (wire (pts (xy 312.42 66.04) (xy 312.42 63.5))
    (stroke (width 0) (type default))
  )
  (wire (pts (xy 17.78 119.38) (xy 17.78 118.11))
    (stroke (width 0) (type default))
  )
  (wire (pts (xy 168.91 227.33) (xy 168.91 224.79))
    (stroke (width 0) (type default))
  )
  (wire (pts (xy 312.42 73.66) (xy 312.42 74.93))
    (stroke (width 0) (type default))
  )
  (wire (pts (xy 330.2 293.37) (xy 326.39 293.37))
    (stroke (width 0) (type default))
  )
  (wire (pts (xy 334.645 149.86) (xy 325.12 149.86))
    (stroke (width 0) (type default))
  )
  (wire (pts (xy 335.915 149.86) (xy 334.645 149.86))
    (stroke (width 0) (type default))
  )
  (wire (pts (xy 90.17 54.61) (xy 99.06 54.61))
    (stroke (width 0) (type default))
  )
  (wire (pts (xy 165.1 349.25) (xy 162.56 349.25))
    (stroke (width 0) (type default))
  )
  (wire (pts (xy 523.24 256.54) (xy 566.42 256.54))
    (stroke (width 0) (type default))
  )
  (wire (pts (xy 168.91 232.41) (xy 168.91 234.95))
    (stroke (width 0) (type default))
  )
  (wire (pts (xy 176.53 262.89) (xy 176.53 264.16))
    (stroke (width 0) (type default))
  )
  (wire (pts (xy 99.06 46.99) (xy 90.17 46.99))
    (stroke (width 0) (type default))
  )
  (wire (pts (xy 530.86 153.67) (xy 530.86 156.21))
    (stroke (width 0) (type default))
  )
  (polyline (pts (xy 223.52 189.23) (xy 223.52 107.95))
    (stroke (width 0) (type default))
  )

  (wire (pts (xy 434.34 284.48) (xy 459.74 284.48))
    (stroke (width 0) (type default))
  )
  (wire (pts (xy 523.24 347.98) (xy 524.51 347.98))
    (stroke (width 0) (type default))
  )
  (wire (pts (xy 228.6 337.82) (xy 228.6 339.09))
    (stroke (width 0) (type default))
  )
  (wire (pts (xy 35.56 154.94) (xy 43.18 154.94))
    (stroke (width 0) (type default))
  )
  (wire (pts (xy 543.56 152.4) (xy 543.56 153.67))
    (stroke (width 0) (type default))
  )
  (wire (pts (xy 90.17 74.93) (xy 120.65 74.93))
    (stroke (width 0) (type default))
  )
  (wire (pts (xy 167.64 303.53) (xy 175.26 303.53))
    (stroke (width 0) (type default))
  )
  (wire (pts (xy 459.74 347.98) (xy 434.34 347.98))
    (stroke (width 0) (type default))
  )
  (wire (pts (xy 330.2 293.37) (xy 334.01 293.37))
    (stroke (width 0) (type default))
  )
  (wire (pts (xy 57.15 64.77) (xy 63.5 64.77))
    (stroke (width 0) (type default))
  )
  (wire (pts (xy 386.08 322.58) (xy 386.08 326.39))
    (stroke (width 0) (type default))
  )
  (wire (pts (xy 530.86 161.29) (xy 530.86 167.64))
    (stroke (width 0) (type default))
  )
  (wire (pts (xy 168.91 160.02) (xy 168.91 167.64))
    (stroke (width 0) (type default))
  )
  (wire (pts (xy 246.38 228.6) (xy 246.38 226.06))
    (stroke (width 0) (type default))
  )
  (wire (pts (xy 525.78 251.46) (xy 523.24 251.46))
    (stroke (width 0) (type default))
  )
  (wire (pts (xy 511.81 62.23) (xy 508 62.23))
    (stroke (width 0) (type default))
  )
  (wire (pts (xy 417.83 241.3) (xy 422.91 241.3))
    (stroke (width 0) (type default))
  )
  (wire (pts (xy 384.81 163.83) (xy 401.32 163.83))
    (stroke (width 0) (type default))
  )
  (wire (pts (xy 90.17 133.35) (xy 99.06 133.35))
    (stroke (width 0) (type default))
  )
  (wire (pts (xy 210.82 76.2) (xy 227.33 76.2))
    (stroke (width 0) (type default))
  )
  (wire (pts (xy 283.21 71.12) (xy 275.59 71.12))
    (stroke (width 0) (type default))
  )
  (wire (pts (xy 110.49 156.21) (xy 111.76 156.21))
    (stroke (width 0) (type default))
  )
  (wire (pts (xy 63.5 48.26) (xy 38.1 48.26))
    (stroke (width 0) (type default))
  )
  (wire (pts (xy 44.45 127) (xy 58.42 127))
    (stroke (width 0) (type default))
  )
  (wire (pts (xy 91.44 332.74) (xy 91.44 328.93))
    (stroke (width 0) (type default))
  )
  (wire (pts (xy 57.15 67.31) (xy 63.5 67.31))
    (stroke (width 0) (type default))
  )
  (wire (pts (xy 309.88 66.04) (xy 312.42 66.04))
    (stroke (width 0) (type default))
  )
  (wire (pts (xy 280.67 66.04) (xy 280.67 63.5))
    (stroke (width 0) (type default))
  )
  (wire (pts (xy 265.43 274.32) (xy 288.29 274.32))
    (stroke (width 0) (type default))
  )
  (wire (pts (xy 360.68 384.81) (xy 360.68 383.54))
    (stroke (width 0) (type default))
  )
  (wire (pts (xy 78.74 234.95) (xy 78.74 237.49))
    (stroke (width 0) (type default))
  )
  (wire (pts (xy 170.18 167.64) (xy 168.91 167.64))
    (stroke (width 0) (type default))
  )
  (wire (pts (xy 377.19 35.56) (xy 377.19 38.1))
    (stroke (width 0) (type default))
  )
  (wire (pts (xy 179.07 73.66) (xy 161.29 73.66))
    (stroke (width 0) (type default))
  )
  (wire (pts (xy 530.86 153.67) (xy 537.21 153.67))
    (stroke (width 0) (type default))
  )
  (wire (pts (xy 450.85 241.3) (xy 459.74 241.3))
    (stroke (width 0) (type default))
  )
  (wire (pts (xy 444.5 107.95) (xy 444.5 160.655))
    (stroke (width 0) (type default))
  )
  (polyline (pts (xy 299.72 266.7) (xy 407.67 266.7))
    (stroke (width 0) (type default))
  )

  (wire (pts (xy 146.05 149.86) (xy 146.05 152.4))
    (stroke (width 0) (type default))
  )
  (wire (pts (xy 270.51 378.46) (xy 278.765 378.46))
    (stroke (width 0) (type default))
  )
  (wire (pts (xy 153.67 264.16) (xy 153.67 266.7))
    (stroke (width 0) (type default))
  )
  (wire (pts (xy 422.91 243.84) (xy 417.83 243.84))
    (stroke (width 0) (type default))
  )
  (polyline (pts (xy 64.77 107.95) (xy 64.77 189.23))
    (stroke (width 0) (type default))
  )

  (wire (pts (xy 90.17 90.17) (xy 120.65 90.17))
    (stroke (width 0) (type default))
  )
  (wire (pts (xy 372.11 222.25) (xy 372.11 224.79))
    (stroke (width 0) (type default))
  )
  (wire (pts (xy 17.78 119.38) (xy 34.29 119.38))
    (stroke (width 0) (type default))
  )
  (wire (pts (xy 377.19 113.03) (xy 381 113.03))
    (stroke (width 0) (type default))
  )
  (wire (pts (xy 439.42 133.35) (xy 450.85 133.35))
    (stroke (width 0) (type default))
  )
  (wire (pts (xy 271.78 140.97) (xy 271.78 146.05))
    (stroke (width 0) (type default))
  )
  (wire (pts (xy 523.24 312.42) (xy 566.42 312.42))
    (stroke (width 0) (type default))
  )
  (wire (pts (xy 415.29 135.89) (xy 434.34 135.89))
    (stroke (width 0) (type default))
  )
  (wire (pts (xy 144.78 300.99) (xy 144.78 303.53))
    (stroke (width 0) (type default))
  )
  (wire (pts (xy 516.89 64.77) (xy 520.7 64.77))
    (stroke (width 0) (type default))
  )
  (wire (pts (xy 44.45 129.54) (xy 58.42 129.54))
    (stroke (width 0) (type default))
  )
  (wire (pts (xy 523.24 259.08) (xy 566.42 259.08))
    (stroke (width 0) (type default))
  )
  (wire (pts (xy 374.65 303.53) (xy 374.65 317.5))
    (stroke (width 0) (type default))
  )
  (wire (pts (xy 179.07 80.01) (xy 161.29 80.01))
    (stroke (width 0) (type default))
  )
  (wire (pts (xy 271.78 226.06) (xy 274.32 226.06))
    (stroke (width 0) (type default))
  )
  (wire (pts (xy 434.34 340.36) (xy 459.74 340.36))
    (stroke (width 0) (type default))
  )
  (wire (pts (xy 69.85 233.68) (xy 67.31 233.68))
    (stroke (width 0) (type default))
  )
  (wire (pts (xy 312.42 60.96) (xy 312.42 58.42))
    (stroke (width 0) (type default))
  )
  (wire (pts (xy 90.17 44.45) (xy 99.06 44.45))
    (stroke (width 0) (type default))
  )
  (wire (pts (xy 459.74 274.32) (xy 436.88 274.32))
    (stroke (width 0) (type default))
  )
  (wire (pts (xy 146.05 152.4) (xy 146.05 160.02))
    (stroke (width 0) (type default))
  )
  (wire (pts (xy 269.24 140.97) (xy 271.78 140.97))
    (stroke (width 0) (type default))
  )
  (wire (pts (xy 524.51 170.18) (xy 557.53 170.18))
    (stroke (width 0) (type default))
  )
  (wire (pts (xy 228.6 224.79) (xy 228.6 226.06))
    (stroke (width 0) (type default))
  )
  (wire (pts (xy 532.13 100.33) (xy 506.73 100.33))
    (stroke (width 0) (type default))
  )
  (wire (pts (xy 49.53 332.74) (xy 49.53 328.93))
    (stroke (width 0) (type default))
  )
  (wire (pts (xy 337.82 322.58) (xy 337.82 326.39))
    (stroke (width 0) (type default))
  )
  (wire (pts (xy 144.78 262.89) (xy 144.78 264.16))
    (stroke (width 0) (type default))
  )
  (wire (pts (xy 87.63 241.3) (xy 87.63 247.65))
    (stroke (width 0) (type default))
  )
  (bus (pts (xy 431.8 281.94) (xy 431.8 284.48))
    (stroke (width 0) (type default))
  )

  (wire (pts (xy 523.24 304.8) (xy 566.42 304.8))
    (stroke (width 0) (type default))
  )
  (wire (pts (xy 548.64 46.99) (xy 565.15 46.99))
    (stroke (width 0) (type default))
  )
  (wire (pts (xy 137.16 158.75) (xy 134.62 158.75))
    (stroke (width 0) (type default))
  )
  (wire (pts (xy 146.05 160.02) (xy 168.91 160.02))
    (stroke (width 0) (type default))
  )
  (wire (pts (xy 34.29 332.74) (xy 34.29 328.93))
    (stroke (width 0) (type default))
  )
  (wire (pts (xy 325.12 149.86) (xy 325.12 152.4))
    (stroke (width 0) (type default))
  )
  (wire (pts (xy 330.2 306.07) (xy 330.2 317.5))
    (stroke (width 0) (type default))
  )
  (wire (pts (xy 341.63 293.37) (xy 345.44 293.37))
    (stroke (width 0) (type default))
  )
  (wire (pts (xy 210.82 68.58) (xy 227.33 68.58))
    (stroke (width 0) (type default))
  )
  (wire (pts (xy 154.94 349.25) (xy 157.48 349.25))
    (stroke (width 0) (type default))
  )
  (wire (pts (xy 386.08 299.72) (xy 386.08 311.15))
    (stroke (width 0) (type default))
  )
  (wire (pts (xy 382.27 293.37) (xy 382.27 294.64))
    (stroke (width 0) (type default))
  )
  (wire (pts (xy 523.24 281.94) (xy 552.45 281.94))
    (stroke (width 0) (type default))
  )
  (wire (pts (xy 506.73 44.45) (xy 506.73 41.91))
    (stroke (width 0) (type default))
  )
  (wire (pts (xy 69.85 243.84) (xy 69.85 246.38))
    (stroke (width 0) (type default))
  )
  (wire (pts (xy 67.31 228.6) (xy 69.85 228.6))
    (stroke (width 0) (type default))
  )
  (wire (pts (xy 177.8 234.95) (xy 177.8 236.22))
    (stroke (width 0) (type default))
  )
  (wire (pts (xy 325.12 149.86) (xy 325.12 147.32))
    (stroke (width 0) (type default))
  )
  (wire (pts (xy 393.7 316.23) (xy 393.7 317.5))
    (stroke (width 0) (type default))
  )
  (wire (pts (xy 538.48 287.02) (xy 538.48 284.48))
    (stroke (width 0) (type default))
  )
  (wire (pts (xy 134.62 149.86) (xy 146.05 149.86))
    (stroke (width 0) (type default))
  )
  (wire (pts (xy 450.85 133.35) (xy 461.01 133.35))
    (stroke (width 0) (type default))
  )
  (wire (pts (xy 378.46 322.58) (xy 378.46 326.39))
    (stroke (width 0) (type default))
  )
  (wire (pts (xy 83.82 304.8) (xy 83.82 302.26))
    (stroke (width 0) (type default))
  )
  (wire (pts (xy 210.82 73.66) (xy 227.33 73.66))
    (stroke (width 0) (type default))
  )
  (wire (pts (xy 228.6 299.72) (xy 228.6 295.91))
    (stroke (width 0) (type default))
  )
  (wire (pts (xy 427.99 254) (xy 459.74 254))
    (stroke (width 0) (type default))
  )
  (wire (pts (xy 330.2 294.64) (xy 330.2 293.37))
    (stroke (width 0) (type default))
  )
  (wire (pts (xy 63.5 82.55) (xy 39.37 82.55))
    (stroke (width 0) (type default))
  )
  (wire (pts (xy 370.84 88.9) (xy 370.84 85.09))
    (stroke (width 0) (type default))
  )
  (wire (pts (xy 523.24 299.72) (xy 566.42 299.72))
    (stroke (width 0) (type default))
  )
  (wire (pts (xy 260.35 299.72) (xy 250.19 299.72))
    (stroke (width 0) (type default))
  )
  (wire (pts (xy 248.92 140.97) (xy 251.46 140.97))
    (stroke (width 0) (type default))
  )
  (wire (pts (xy 459.74 161.29) (xy 461.01 161.29))
    (stroke (width 0) (type default))
  )
  (wire (pts (xy 381 113.03) (xy 381 111.76))
    (stroke (width 0) (type default))
  )
  (wire (pts (xy 307.34 311.15) (xy 337.82 311.15))
    (stroke (width 0) (type default))
  )
  (wire (pts (xy 154.94 144.78) (xy 156.21 144.78))
    (stroke (width 0) (type default))
  )
  (wire (pts (xy 146.05 144.78) (xy 146.05 147.32))
    (stroke (width 0) (type default))
  )
  (bus (pts (xy 431.8 289.56) (xy 431.8 292.1))
    (stroke (width 0) (type default))
  )

  (wire (pts (xy 337.82 203.2) (xy 326.39 203.2))
    (stroke (width 0) (type default))
  )
  (wire (pts (xy 378.46 85.09) (xy 391.16 85.09))
    (stroke (width 0) (type default))
  )
  (wire (pts (xy 161.29 53.34) (xy 179.07 53.34))
    (stroke (width 0) (type default))
  )
  (wire (pts (xy 381 105.41) (xy 394.97 105.41))
    (stroke (width 0) (type default))
  )
  (wire (pts (xy 439.42 151.13) (xy 458.47 151.13))
    (stroke (width 0) (type default))
  )
  (wire (pts (xy 271.78 266.7) (xy 275.59 266.7))
    (stroke (width 0) (type default))
  )
  (wire (pts (xy 153.67 224.79) (xy 158.75 224.79))
    (stroke (width 0) (type default))
  )
  (wire (pts (xy 434.34 299.72) (xy 459.74 299.72))
    (stroke (width 0) (type default))
  )
  (wire (pts (xy 256.54 274.32) (xy 265.43 274.32))
    (stroke (width 0) (type default))
  )
  (wire (pts (xy 524.51 161.29) (xy 524.51 170.18))
    (stroke (width 0) (type default))
  )
  (wire (pts (xy 336.55 369.57) (xy 346.71 369.57))
    (stroke (width 0) (type default))
  )
  (wire (pts (xy 461.01 105.41) (xy 448.31 105.41))
    (stroke (width 0) (type default))
  )
  (wire (pts (xy 276.86 58.42) (xy 283.21 58.42))
    (stroke (width 0) (type default))
  )
  (wire (pts (xy 355.6 311.15) (xy 386.08 311.15))
    (stroke (width 0) (type default))
  )
  (wire (pts (xy 374.65 326.39) (xy 378.46 326.39))
    (stroke (width 0) (type default))
  )
  (wire (pts (xy 453.39 125.73) (xy 453.39 130.81))
    (stroke (width 0) (type default))
  )
  (wire (pts (xy 345.44 316.23) (xy 345.44 317.5))
    (stroke (width 0) (type default))
  )
  (wire (pts (xy 523.24 241.3) (xy 528.32 241.3))
    (stroke (width 0) (type default))
  )
  (wire (pts (xy 259.08 140.97) (xy 264.16 140.97))
    (stroke (width 0) (type default))
  )
  (wire (pts (xy 146.05 137.16) (xy 170.18 137.16))
    (stroke (width 0) (type default))
  )
  (wire (pts (xy 537.21 156.21) (xy 537.21 153.67))
    (stroke (width 0) (type default))
  )
  (wire (pts (xy 506.73 41.91) (xy 506.73 39.37))
    (stroke (width 0) (type default))
  )
  (polyline (pts (xy 407.67 189.23) (xy 407.67 11.43))
    (stroke (width 0) (type default))
  )

  (wire (pts (xy 461.01 62.23) (xy 444.5 62.23))
    (stroke (width 0) (type default))
  )
  (wire (pts (xy 309.88 68.58) (xy 312.42 68.58))
    (stroke (width 0) (type default))
  )
  (wire (pts (xy 415.29 133.35) (xy 434.34 133.35))
    (stroke (width 0) (type default))
  )
  (wire (pts (xy 373.38 163.83) (xy 373.38 161.29))
    (stroke (width 0) (type default))
  )
  (wire (pts (xy 69.85 241.3) (xy 69.85 243.84))
    (stroke (width 0) (type default))
  )
  (wire (pts (xy 270.51 372.11) (xy 278.765 372.11))
    (stroke (width 0) (type default))
  )
  (wire (pts (xy 251.46 339.09) (xy 254 339.09))
    (stroke (width 0) (type default))
  )
  (wire (pts (xy 508 64.77) (xy 511.81 64.77))
    (stroke (width 0) (type default))
  )
  (wire (pts (xy 185.42 300.355) (xy 185.42 303.53))
    (stroke (width 0) (type default))
  )
  (wire (pts (xy 351.79 369.57) (xy 360.68 369.57))
    (stroke (width 0) (type default))
  )
  (wire (pts (xy 461.01 41.91) (xy 448.31 41.91))
    (stroke (width 0) (type default))
  )
  (wire (pts (xy 523.24 284.48) (xy 538.48 284.48))
    (stroke (width 0) (type default))
  )
  (wire (pts (xy 17.78 127) (xy 34.29 127))
    (stroke (width 0) (type default))
  )
  (wire (pts (xy 444.5 54.61) (xy 444.5 62.23))
    (stroke (width 0) (type default))
  )
  (wire (pts (xy 146.05 137.16) (xy 146.05 144.78))
    (stroke (width 0) (type default))
  )
  (wire (pts (xy 110.49 165.1) (xy 110.49 162.56))
    (stroke (width 0) (type default))
  )
  (wire (pts (xy 177.8 224.79) (xy 168.91 224.79))
    (stroke (width 0) (type default))
  )
  (wire (pts (xy 434.34 162.56) (xy 434.34 160.655))
    (stroke (width 0) (type default))
  )
  (wire (pts (xy 346.71 251.46) (xy 354.33 251.46))
    (stroke (width 0) (type default))
  )
  (wire (pts (xy 153.67 234.95) (xy 144.78 234.95))
    (stroke (width 0) (type default))
  )
  (wire (pts (xy 99.06 67.31) (xy 90.17 67.31))
    (stroke (width 0) (type default))
  )
  (bus (pts (xy 416.56 261.62) (xy 429.26 261.62))
    (stroke (width 0) (type default))
  )

  (wire (pts (xy 168.91 264.16) (xy 176.53 264.16))
    (stroke (width 0) (type default))
  )
  (wire (pts (xy 523.24 345.44) (xy 537.21 345.44))
    (stroke (width 0) (type default))
  )
  (wire (pts (xy 330.2 299.72) (xy 330.2 306.07))
    (stroke (width 0) (type default))
  )
  (wire (pts (xy 90.17 85.09) (xy 120.65 85.09))
    (stroke (width 0) (type default))
  )
  (bus (pts (xy 431.8 279.4) (xy 431.8 281.94))
    (stroke (width 0) (type default))
  )

  (wire (pts (xy 43.18 157.48) (xy 35.56 157.48))
    (stroke (width 0) (type default))
  )
  (wire (pts (xy 259.08 140.97) (xy 259.08 142.24))
    (stroke (width 0) (type default))
  )
  (wire (pts (xy 341.63 313.69) (xy 341.63 317.5))
    (stroke (width 0) (type default))
  )
  (wire (pts (xy 144.78 232.41) (xy 144.78 234.95))
    (stroke (width 0) (type default))
  )
  (wire (pts (xy 99.06 52.07) (xy 90.17 52.07))
    (stroke (width 0) (type default))
  )
  (wire (pts (xy 52.07 69.85) (xy 25.4 69.85))
    (stroke (width 0) (type default))
  )
  (wire (pts (xy 269.24 60.96) (xy 283.21 60.96))
    (stroke (width 0) (type default))
  )
  (polyline (pts (xy 64.77 173.99) (xy 12.7 173.99))
    (stroke (width 0) (type default))
  )

  (wire (pts (xy 76.2 302.26) (xy 76.2 300.99))
    (stroke (width 0) (type default))
  )
  (wire (pts (xy 161.29 60.96) (xy 179.07 60.96))
    (stroke (width 0) (type default))
  )
  (wire (pts (xy 518.16 44.45) (xy 520.7 44.45))
    (stroke (width 0) (type default))
  )
  (wire (pts (xy 175.26 160.02) (xy 176.53 160.02))
    (stroke (width 0) (type default))
  )
  (wire (pts (xy 110.49 165.1) (xy 111.76 165.1))
    (stroke (width 0) (type default))
  )
  (wire (pts (xy 524.51 347.98) (xy 524.51 349.25))
    (stroke (width 0) (type default))
  )
  (wire (pts (xy 461.01 151.13) (xy 458.47 151.13))
    (stroke (width 0) (type default))
  )
  (polyline (pts (xy 535.94 154.94) (xy 535.94 162.56))
    (stroke (width 0) (type default))
  )

  (bus (pts (xy 123.19 82.55) (xy 123.19 85.09))
    (stroke (width 0) (type default))
  )

  (wire (pts (xy 328.93 222.25) (xy 341.63 222.25))
    (stroke (width 0) (type default))
  )
  (wire (pts (xy 363.22 35.56) (xy 369.57 35.56))
    (stroke (width 0) (type default))
  )
  (wire (pts (xy 368.3 326.39) (xy 368.3 328.93))
    (stroke (width 0) (type default))
  )
  (wire (pts (xy 78.74 245.11) (xy 78.74 247.65))
    (stroke (width 0) (type default))
  )
  (wire (pts (xy 187.96 234.95) (xy 177.8 234.95))
    (stroke (width 0) (type default))
  )
  (wire (pts (xy 370.84 85.09) (xy 373.38 85.09))
    (stroke (width 0) (type default))
  )
  (wire (pts (xy 439.42 138.43) (xy 461.01 138.43))
    (stroke (width 0) (type default))
  )
  (wire (pts (xy 459.74 271.78) (xy 436.88 271.78))
    (stroke (width 0) (type default))
  )
  (wire (pts (xy 345.44 299.72) (xy 345.44 316.23))
    (stroke (width 0) (type default))
  )
  (wire (pts (xy 144.78 264.16) (xy 144.78 266.7))
    (stroke (width 0) (type default))
  )
  (wire (pts (xy 361.95 222.25) (xy 372.11 222.25))
    (stroke (width 0) (type default))
  )
  (wire (pts (xy 146.05 144.78) (xy 147.32 144.78))
    (stroke (width 0) (type default))
  )
  (wire (pts (xy 271.78 149.86) (xy 284.48 149.86))
    (stroke (width 0) (type default))
  )
  (wire (pts (xy 210.82 60.96) (xy 227.33 60.96))
    (stroke (width 0) (type default))
  )
  (wire (pts (xy 318.77 68.58) (xy 312.42 68.58))
    (stroke (width 0) (type default))
  )
  (wire (pts (xy 459.74 269.24) (xy 436.88 269.24))
    (stroke (width 0) (type default))
  )
  (wire (pts (xy 381 113.03) (xy 394.97 113.03))
    (stroke (width 0) (type default))
  )
  (wire (pts (xy 41.91 302.26) (xy 34.29 302.26))
    (stroke (width 0) (type default))
  )
  (wire (pts (xy 57.15 332.74) (xy 57.15 328.93))
    (stroke (width 0) (type default))
  )
  (wire (pts (xy 415.29 138.43) (xy 434.34 138.43))
    (stroke (width 0) (type default))
  )
  (bus (pts (xy 431.8 284.48) (xy 431.8 287.02))
    (stroke (width 0) (type default))
  )

  (wire (pts (xy 182.88 160.02) (xy 189.23 160.02))
    (stroke (width 0) (type default))
  )
  (wire (pts (xy 34.29 302.26) (xy 34.29 304.8))
    (stroke (width 0) (type default))
  )
  (wire (pts (xy 90.17 69.85) (xy 120.65 69.85))
    (stroke (width 0) (type default))
  )
  (wire (pts (xy 152.4 144.78) (xy 154.94 144.78))
    (stroke (width 0) (type default))
  )
  (wire (pts (xy 381 106.68) (xy 381 105.41))
    (stroke (width 0) (type default))
  )
  (wire (pts (xy 459.74 246.38) (xy 433.07 246.38))
    (stroke (width 0) (type default))
  )
  (wire (pts (xy 542.29 107.95) (xy 567.69 107.95))
    (stroke (width 0) (type default))
  )
  (wire (pts (xy 532.13 102.87) (xy 506.73 102.87))
    (stroke (width 0) (type default))
  )
  (wire (pts (xy 161.29 144.78) (xy 162.56 144.78))
    (stroke (width 0) (type default))
  )
  (wire (pts (xy 330.2 322.58) (xy 330.2 326.39))
    (stroke (width 0) (type default))
  )
  (polyline (pts (xy 408.94 118.11) (xy 408.94 128.27))
    (stroke (width 0) (type dash_dot))
  )

  (wire (pts (xy 378.46 294.64) (xy 378.46 293.37))
    (stroke (width 0) (type default))
  )
  (wire (pts (xy 137.16 166.37) (xy 137.16 158.75))
    (stroke (width 0) (type default))
  )
  (wire (pts (xy 261.62 372.11) (xy 261.62 378.46))
    (stroke (width 0) (type default))
  )
  (wire (pts (xy 450.85 128.27) (xy 450.85 133.35))
    (stroke (width 0) (type default))
  )
  (polyline (pts (xy 500.38 154.94) (xy 535.94 154.94))
    (stroke (width 0) (type default))
  )

  (wire (pts (xy 144.78 222.25) (xy 144.78 224.79))
    (stroke (width 0) (type default))
  )
  (wire (pts (xy 373.38 163.83) (xy 379.73 163.83))
    (stroke (width 0) (type default))
  )
  (wire (pts (xy 17.78 129.54) (xy 34.29 129.54))
    (stroke (width 0) (type default))
  )
  (wire (pts (xy 341.63 293.37) (xy 341.63 294.64))
    (stroke (width 0) (type default))
  )
  (wire (pts (xy 513.08 44.45) (xy 506.73 44.45))
    (stroke (width 0) (type default))
  )
  (wire (pts (xy 99.06 153.67) (xy 111.76 153.67))
    (stroke (width 0) (type default))
  )
  (wire (pts (xy 87.63 228.6) (xy 87.63 236.22))
    (stroke (width 0) (type default))
  )
  (wire (pts (xy 146.05 152.4) (xy 147.32 152.4))
    (stroke (width 0) (type default))
  )
  (wire (pts (xy 508 68.58) (xy 508 64.77))
    (stroke (width 0) (type default))
  )
  (wire (pts (xy 445.77 350.52) (xy 459.74 350.52))
    (stroke (width 0) (type default))
  )
  (wire (pts (xy 509.27 54.61) (xy 520.7 54.61))
    (stroke (width 0) (type default))
  )
  (wire (pts (xy 259.08 133.35) (xy 256.54 133.35))
    (stroke (width 0) (type default))
  )
  (wire (pts (xy 523.24 261.62) (xy 566.42 261.62))
    (stroke (width 0) (type default))
  )
  (wire (pts (xy 111.76 143.51) (xy 106.68 143.51))
    (stroke (width 0) (type default))
  )
  (wire (pts (xy 328.93 236.22) (xy 341.63 236.22))
    (stroke (width 0) (type default))
  )
  (wire (pts (xy 363.22 373.38) (xy 363.22 369.57))
    (stroke (width 0) (type default))
  )
  (wire (pts (xy 161.29 50.8) (xy 179.07 50.8))
    (stroke (width 0) (type default))
  )
  (wire (pts (xy 49.53 233.68) (xy 49.53 228.6))
    (stroke (width 0) (type default))
  )
  (wire (pts (xy 36.83 228.6) (xy 36.83 226.06))
    (stroke (width 0) (type default))
  )
  (wire (pts (xy 444.5 69.85) (xy 444.5 77.47))
    (stroke (width 0) (type default))
  )
  (wire (pts (xy 250.19 300.99) (xy 250.19 299.72))
    (stroke (width 0) (type default))
  )
  (wire (pts (xy 523.24 317.5) (xy 566.42 317.5))
    (stroke (width 0) (type default))
  )
  (wire (pts (xy 176.53 160.02) (xy 176.53 167.64))
    (stroke (width 0) (type default))
  )
  (wire (pts (xy 90.17 62.23) (xy 99.06 62.23))
    (stroke (width 0) (type default))
  )
  (wire (pts (xy 152.4 306.07) (xy 152.4 303.53))
    (stroke (width 0) (type default))
  )
  (wire (pts (xy 506.73 41.91) (xy 520.7 41.91))
    (stroke (width 0) (type default))
  )
  (wire (pts (xy 461.01 80.01) (xy 448.31 80.01))
    (stroke (width 0) (type default))
  )
  (wire (pts (xy 161.29 152.4) (xy 162.56 152.4))
    (stroke (width 0) (type default))
  )
  (wire (pts (xy 523.24 274.32) (xy 566.42 274.32))
    (stroke (width 0) (type default))
  )
  (polyline (pts (xy 443.23 128.27) (xy 408.94 128.27))
    (stroke (width 0) (type dash_dot))
  )

  (wire (pts (xy 175.26 303.53) (xy 175.26 306.07))
    (stroke (width 0) (type default))
  )
  (wire (pts (xy 246.38 274.32) (xy 246.38 273.05))
    (stroke (width 0) (type default))
  )
  (wire (pts (xy 461.01 36.83) (xy 448.31 36.83))
    (stroke (width 0) (type default))
  )
  (wire (pts (xy 69.85 246.38) (xy 67.31 246.38))
    (stroke (width 0) (type default))
  )
  (wire (pts (xy 433.07 256.54) (xy 450.85 256.54))
    (stroke (width 0) (type default))
  )
  (wire (pts (xy 210.82 81.28) (xy 227.33 81.28))
    (stroke (width 0) (type default))
  )
  (wire (pts (xy 17.78 121.92) (xy 34.29 121.92))
    (stroke (width 0) (type default))
  )
  (wire (pts (xy 312.42 73.66) (xy 309.88 73.66))
    (stroke (width 0) (type default))
  )
  (wire (pts (xy 256.54 226.06) (xy 265.43 226.06))
    (stroke (width 0) (type default))
  )
  (wire (pts (xy 49.53 304.8) (xy 49.53 302.26))
    (stroke (width 0) (type default))
  )
  (wire (pts (xy 256.54 267.97) (xy 256.54 266.7))
    (stroke (width 0) (type default))
  )
  (wire (pts (xy 434.34 309.88) (xy 459.74 309.88))
    (stroke (width 0) (type default))
  )
  (wire (pts (xy 422.91 254) (xy 417.83 254))
    (stroke (width 0) (type default))
  )
  (wire (pts (xy 265.43 273.05) (xy 265.43 274.32))
    (stroke (width 0) (type default))
  )
  (wire (pts (xy 389.89 326.39) (xy 393.7 326.39))
    (stroke (width 0) (type default))
  )
  (wire (pts (xy 210.82 83.82) (xy 227.33 83.82))
    (stroke (width 0) (type default))
  )
  (wire (pts (xy 439.42 135.89) (xy 461.01 135.89))
    (stroke (width 0) (type default))
  )
  (wire (pts (xy 461.01 46.99) (xy 448.31 46.99))
    (stroke (width 0) (type default))
  )
  (wire (pts (xy 523.24 314.96) (xy 566.42 314.96))
    (stroke (width 0) (type default))
  )
  (wire (pts (xy 236.22 347.98) (xy 236.22 345.44))
    (stroke (width 0) (type default))
  )
  (wire (pts (xy 44.45 119.38) (xy 58.42 119.38))
    (stroke (width 0) (type default))
  )
  (wire (pts (xy 274.32 226.06) (xy 276.86 226.06))
    (stroke (width 0) (type default))
  )
  (polyline (pts (xy 485.14 85.09) (xy 581.66 85.09))
    (stroke (width 0) (type default))
  )

  (wire (pts (xy 434.34 337.82) (xy 459.74 337.82))
    (stroke (width 0) (type default))
  )
  (wire (pts (xy 334.645 140.97) (xy 334.645 149.86))
    (stroke (width 0) (type default))
  )
  (wire (pts (xy 43.18 162.56) (xy 43.18 165.1))
    (stroke (width 0) (type default))
  )
  (bus (pts (xy 431.8 276.86) (xy 431.8 279.4))
    (stroke (width 0) (type default))
  )

  (wire (pts (xy 210.82 50.8) (xy 227.33 50.8))
    (stroke (width 0) (type default))
  )
  (wire (pts (xy 516.89 59.69) (xy 520.7 59.69))
    (stroke (width 0) (type default))
  )
  (wire (pts (xy 523.24 320.04) (xy 552.45 320.04))
    (stroke (width 0) (type default))
  )
  (wire (pts (xy 90.17 92.71) (xy 120.65 92.71))
    (stroke (width 0) (type default))
  )
  (wire (pts (xy 90.17 49.53) (xy 99.06 49.53))
    (stroke (width 0) (type default))
  )
  (wire (pts (xy 154.94 143.51) (xy 154.94 144.78))
    (stroke (width 0) (type default))
  )
  (wire (pts (xy 58.42 129.54) (xy 58.42 130.81))
    (stroke (width 0) (type default))
  )
  (wire (pts (xy 523.24 269.24) (xy 566.42 269.24))
    (stroke (width 0) (type default))
  )
  (wire (pts (xy 78.74 237.49) (xy 78.74 240.03))
    (stroke (width 0) (type default))
  )
  (wire (pts (xy 419.1 151.13) (xy 427.99 151.13))
    (stroke (width 0) (type default))
  )
  (wire (pts (xy 163.83 234.95) (xy 168.91 234.95))
    (stroke (width 0) (type default))
  )
  (wire (pts (xy 134.62 147.32) (xy 146.05 147.32))
    (stroke (width 0) (type default))
  )
  (wire (pts (xy 309.88 71.12) (xy 312.42 71.12))
    (stroke (width 0) (type default))
  )
  (wire (pts (xy 256.54 266.7) (xy 265.43 266.7))
    (stroke (width 0) (type default))
  )
  (wire (pts (xy 337.82 212.09) (xy 337.82 215.9))
    (stroke (width 0) (type default))
  )
  (wire (pts (xy 427.99 243.84) (xy 459.74 243.84))
    (stroke (width 0) (type default))
  )
  (wire (pts (xy 279.4 73.66) (xy 283.21 73.66))
    (stroke (width 0) (type default))
  )
  (wire (pts (xy 381 77.47) (xy 381 80.01))
    (stroke (width 0) (type default))
  )
  (wire (pts (xy 459.74 317.5) (xy 434.34 317.5))
    (stroke (width 0) (type default))
  )
  (wire (pts (xy 210.82 53.34) (xy 227.33 53.34))
    (stroke (width 0) (type default))
  )
  (wire (pts (xy 177.8 232.41) (xy 177.8 234.95))
    (stroke (width 0) (type default))
  )
  (wire (pts (xy 374.65 299.72) (xy 374.65 303.53))
    (stroke (width 0) (type default))
  )
  (wire (pts (xy 337.82 299.72) (xy 337.82 311.15))
    (stroke (width 0) (type default))
  )
  (wire (pts (xy 67.31 243.84) (xy 69.85 243.84))
    (stroke (width 0) (type default))
  )
  (bus (pts (xy 125.73 64.77) (xy 139.7 64.77))
    (stroke (width 0) (type default))
  )

  (wire (pts (xy 259.08 163.83) (xy 259.08 162.56))
    (stroke (width 0) (type default))
  )
  (wire (pts (xy 76.2 328.93) (xy 76.2 327.66))
    (stroke (width 0) (type default))
  )
  (wire (pts (xy 459.74 266.7) (xy 434.34 266.7))
    (stroke (width 0) (type default))
  )
  (wire (pts (xy 360.68 388.62) (xy 360.68 384.81))
    (stroke (width 0) (type default))
  )
  (wire (pts (xy 91.44 302.26) (xy 83.82 302.26))
    (stroke (width 0) (type default))
  )
  (wire (pts (xy 259.08 148.59) (xy 259.08 147.32))
    (stroke (width 0) (type default))
  )
  (wire (pts (xy 543.56 162.56) (xy 543.56 161.29))
    (stroke (width 0) (type default))
  )
  (wire (pts (xy 250.19 299.72) (xy 238.76 299.72))
    (stroke (width 0) (type default))
  )
  (wire (pts (xy 99.06 64.77) (xy 90.17 64.77))
    (stroke (width 0) (type default))
  )
  (wire (pts (xy 237.49 274.32) (xy 237.49 273.05))
    (stroke (width 0) (type default))
  )
  (wire (pts (xy 509.27 52.07) (xy 520.7 52.07))
    (stroke (width 0) (type default))
  )
  (wire (pts (xy 318.77 74.93) (xy 318.77 68.58))
    (stroke (width 0) (type default))
  )
  (wire (pts (xy 63.5 74.93) (xy 39.37 74.93))
    (stroke (width 0) (type default))
  )
  (wire (pts (xy 228.6 219.71) (xy 228.6 218.44))
    (stroke (width 0) (type default))
  )
  (wire (pts (xy 153.67 234.95) (xy 153.67 232.41))
    (stroke (width 0) (type default))
  )
  (wire (pts (xy 393.7 293.37) (xy 393.7 294.64))
    (stroke (width 0) (type default))
  )
  (wire (pts (xy 461.01 57.15) (xy 448.31 57.15))
    (stroke (width 0) (type default))
  )
  (wire (pts (xy 334.01 293.37) (xy 337.82 293.37))
    (stroke (width 0) (type default))
  )
  (wire (pts (xy 275.59 71.12) (xy 275.59 69.85))
    (stroke (width 0) (type default))
  )
  (wire (pts (xy 461.01 69.85) (xy 444.5 69.85))
    (stroke (width 0) (type default))
  )
  (wire (pts (xy 386.08 311.15) (xy 386.08 317.5))
    (stroke (width 0) (type default))
  )
  (wire (pts (xy 373.38 152.4) (xy 373.38 156.21))
    (stroke (width 0) (type default))
  )
  (wire (pts (xy 90.17 87.63) (xy 120.65 87.63))
    (stroke (width 0) (type default))
  )
  (wire (pts (xy 283.21 68.58) (xy 280.67 68.58))
    (stroke (width 0) (type default))
  )
  (wire (pts (xy 91.44 304.8) (xy 91.44 302.26))
    (stroke (width 0) (type default))
  )
  (wire (pts (xy 360.68 163.83) (xy 373.38 163.83))
    (stroke (width 0) (type default))
  )
  (wire (pts (xy 312.42 68.58) (xy 312.42 66.04))
    (stroke (width 0) (type default))
  )
  (wire (pts (xy 434.34 279.4) (xy 459.74 279.4))
    (stroke (width 0) (type default))
  )
  (wire (pts (xy 360.68 369.57) (xy 360.68 373.38))
    (stroke (width 0) (type default))
  )
  (wire (pts (xy 237.49 226.06) (xy 246.38 226.06))
    (stroke (width 0) (type default))
  )
  (wire (pts (xy 52.07 67.31) (xy 25.4 67.31))
    (stroke (width 0) (type default))
  )
  (wire (pts (xy 179.07 71.12) (xy 161.29 71.12))
    (stroke (width 0) (type default))
  )
  (wire (pts (xy 307.34 303.53) (xy 326.39 303.53))
    (stroke (width 0) (type default))
  )
  (wire (pts (xy 415.29 128.27) (xy 434.34 128.27))
    (stroke (width 0) (type default))
  )
  (wire (pts (xy 154.94 152.4) (xy 154.94 144.78))
    (stroke (width 0) (type default))
  )
  (wire (pts (xy 538.48 287.02) (xy 551.18 287.02))
    (stroke (width 0) (type default))
  )
  (wire (pts (xy 49.53 302.26) (xy 41.91 302.26))
    (stroke (width 0) (type default))
  )
  (wire (pts (xy 389.89 313.69) (xy 389.89 317.5))
    (stroke (width 0) (type default))
  )
  (wire (pts (xy 95.25 158.75) (xy 101.6 158.75))
    (stroke (width 0) (type default))
  )
  (wire (pts (xy 312.42 63.5) (xy 309.88 63.5))
    (stroke (width 0) (type default))
  )
  (wire (pts (xy 337.82 293.37) (xy 341.63 293.37))
    (stroke (width 0) (type default))
  )
  (wire (pts (xy 186.69 264.16) (xy 176.53 264.16))
    (stroke (width 0) (type default))
  )
  (wire (pts (xy 58.42 121.92) (xy 44.45 121.92))
    (stroke (width 0) (type default))
  )
  (polyline (pts (xy 210.82 400.05) (xy 210.82 203.2))
    (stroke (width 0) (type default))
  )

  (wire (pts (xy 161.29 58.42) (xy 179.07 58.42))
    (stroke (width 0) (type default))
  )
  (wire (pts (xy 543.56 146.05) (xy 543.56 147.32))
    (stroke (width 0) (type default))
  )
  (wire (pts (xy 63.5 44.45) (xy 38.1 44.45))
    (stroke (width 0) (type default))
  )
  (wire (pts (xy 99.06 57.15) (xy 90.17 57.15))
    (stroke (width 0) (type default))
  )
  (wire (pts (xy 237.49 266.7) (xy 246.38 266.7))
    (stroke (width 0) (type default))
  )
  (wire (pts (xy 185.42 303.53) (xy 175.26 303.53))
    (stroke (width 0) (type default))
  )
  (polyline (pts (xy 443.23 118.11) (xy 408.94 118.11))
    (stroke (width 0) (type dash_dot))
  )

  (wire (pts (xy 370.84 88.9) (xy 373.38 88.9))
    (stroke (width 0) (type default))
  )
  (wire (pts (xy 459.74 320.04) (xy 434.34 320.04))
    (stroke (width 0) (type default))
  )
  (wire (pts (xy 506.73 110.49) (xy 506.73 113.03))
    (stroke (width 0) (type default))
  )
  (wire (pts (xy 154.94 152.4) (xy 156.21 152.4))
    (stroke (width 0) (type default))
  )
  (wire (pts (xy 373.38 163.83) (xy 373.38 166.37))
    (stroke (width 0) (type default))
  )
  (wire (pts (xy 90.17 77.47) (xy 120.65 77.47))
    (stroke (width 0) (type default))
  )
  (wire (pts (xy 523.24 264.16) (xy 566.42 264.16))
    (stroke (width 0) (type default))
  )
  (wire (pts (xy 444.5 160.655) (xy 444.5 162.56))
    (stroke (width 0) (type default))
  )
  (wire (pts (xy 248.92 133.35) (xy 248.92 140.97))
    (stroke (width 0) (type default))
  )
  (wire (pts (xy 369.57 114.3) (xy 369.57 113.03))
    (stroke (width 0) (type default))
  )
  (wire (pts (xy 374.65 293.37) (xy 374.65 294.64))
    (stroke (width 0) (type default))
  )
  (wire (pts (xy 278.765 370.84) (xy 278.765 372.11))
    (stroke (width 0) (type default))
  )
  (wire (pts (xy 346.71 203.2) (xy 354.33 203.2))
    (stroke (width 0) (type default))
  )
  (wire (pts (xy 542.29 102.87) (xy 567.69 102.87))
    (stroke (width 0) (type default))
  )
  (wire (pts (xy 461.01 107.95) (xy 444.5 107.95))
    (stroke (width 0) (type default))
  )
  (wire (pts (xy 34.29 124.46) (xy 17.78 124.46))
    (stroke (width 0) (type default))
  )
  (wire (pts (xy 240.03 374.65) (xy 240.03 372.11))
    (stroke (width 0) (type default))
  )
  (wire (pts (xy 63.5 77.47) (xy 39.37 77.47))
    (stroke (width 0) (type default))
  )
  (wire (pts (xy 361.95 203.2) (xy 372.11 203.2))
    (stroke (width 0) (type default))
  )
  (wire (pts (xy 78.74 228.6) (xy 78.74 229.87))
    (stroke (width 0) (type default))
  )
  (wire (pts (xy 434.34 332.74) (xy 459.74 332.74))
    (stroke (width 0) (type default))
  )
  (wire (pts (xy 459.74 345.44) (xy 434.34 345.44))
    (stroke (width 0) (type default))
  )
  (wire (pts (xy 261.62 372.11) (xy 265.43 372.11))
    (stroke (width 0) (type default))
  )
  (wire (pts (xy 43.18 154.94) (xy 43.18 152.4))
    (stroke (width 0) (type default))
  )
  (wire (pts (xy 177.8 224.79) (xy 177.8 227.33))
    (stroke (width 0) (type default))
  )
  (bus (pts (xy 431.8 287.02) (xy 431.8 289.56))
    (stroke (width 0) (type default))
  )

  (wire (pts (xy 182.88 137.16) (xy 184.15 137.16))
    (stroke (width 0) (type default))
  )
  (wire (pts (xy 543.56 162.56) (xy 557.53 162.56))
    (stroke (width 0) (type default))
  )
  (wire (pts (xy 516.89 62.23) (xy 520.7 62.23))
    (stroke (width 0) (type default))
  )
  (bus (pts (xy 123.19 80.01) (xy 123.19 82.55))
    (stroke (width 0) (type default))
  )

  (wire (pts (xy 445.77 302.26) (xy 459.74 302.26))
    (stroke (width 0) (type default))
  )
  (wire (pts (xy 220.98 368.3) (xy 220.98 372.11))
    (stroke (width 0) (type default))
  )
  (wire (pts (xy 63.5 58.42) (xy 38.1 58.42))
    (stroke (width 0) (type default))
  )
  (wire (pts (xy 236.22 339.09) (xy 236.22 340.36))
    (stroke (width 0) (type default))
  )
  (wire (pts (xy 106.68 133.35) (xy 99.06 133.35))
    (stroke (width 0) (type default))
  )
  (wire (pts (xy 434.34 281.94) (xy 459.74 281.94))
    (stroke (width 0) (type default))
  )
  (wire (pts (xy 361.95 251.46) (xy 372.11 251.46))
    (stroke (width 0) (type default))
  )
  (wire (pts (xy 110.49 162.56) (xy 110.49 156.21))
    (stroke (width 0) (type default))
  )
  (wire (pts (xy 259.08 140.97) (xy 256.54 140.97))
    (stroke (width 0) (type default))
  )
  (wire (pts (xy 144.78 264.16) (xy 153.67 264.16))
    (stroke (width 0) (type default))
  )
  (wire (pts (xy 433.07 259.08) (xy 459.74 259.08))
    (stroke (width 0) (type default))
  )
  (wire (pts (xy 278.765 379.73) (xy 278.765 378.46))
    (stroke (width 0) (type default))
  )
  (wire (pts (xy 307.34 313.69) (xy 341.63 313.69))
    (stroke (width 0) (type default))
  )
  (wire (pts (xy 389.89 322.58) (xy 389.89 326.39))
    (stroke (width 0) (type default))
  )
  (wire (pts (xy 276.86 58.42) (xy 276.86 49.53))
    (stroke (width 0) (type default))
  )
  (bus (pts (xy 123.19 74.93) (xy 123.19 77.47))
    (stroke (width 0) (type default))
  )

  (wire (pts (xy 320.04 326.39) (xy 320.04 328.93))
    (stroke (width 0) (type default))
  )
  (wire (pts (xy 271.78 146.05) (xy 284.48 146.05))
    (stroke (width 0) (type default))
  )
  (wire (pts (xy 389.89 293.37) (xy 393.7 293.37))
    (stroke (width 0) (type default))
  )
  (wire (pts (xy 83.82 328.93) (xy 76.2 328.93))
    (stroke (width 0) (type default))
  )
  (wire (pts (xy 461.01 87.63) (xy 448.31 87.63))
    (stroke (width 0) (type default))
  )
  (wire (pts (xy 260.35 300.99) (xy 260.35 299.72))
    (stroke (width 0) (type default))
  )
  (wire (pts (xy 434.34 160.655) (xy 444.5 160.655))
    (stroke (width 0) (type default))
  )
  (wire (pts (xy 417.83 241.3) (xy 417.83 236.22))
    (stroke (width 0) (type default))
  )
  (wire (pts (xy 90.17 149.86) (xy 111.76 149.86))
    (stroke (width 0) (type default))
  )
  (wire (pts (xy 238.76 299.72) (xy 228.6 299.72))
    (stroke (width 0) (type default))
  )
  (wire (pts (xy 444.5 62.23) (xy 444.5 69.85))
    (stroke (width 0) (type default))
  )
  (wire (pts (xy 158.75 234.95) (xy 153.67 234.95))
    (stroke (width 0) (type default))
  )
  (wire (pts (xy 523.24 297.18) (xy 566.42 297.18))
    (stroke (width 0) (type default))
  )
  (wire (pts (xy 265.43 226.06) (xy 271.78 226.06))
    (stroke (width 0) (type default))
  )
  (wire (pts (xy 382.27 299.72) (xy 382.27 308.61))
    (stroke (width 0) (type default))
  )
  (wire (pts (xy 372.11 203.2) (xy 372.11 205.74))
    (stroke (width 0) (type default))
  )
  (polyline (pts (xy 407.67 132.08) (xy 355.6 132.08))
    (stroke (width 0) (type default))
  )
  (polyline (pts (xy 535.94 162.56) (xy 500.38 162.56))
    (stroke (width 0) (type default))
  )

  (wire (pts (xy 326.39 303.53) (xy 326.39 317.5))
    (stroke (width 0) (type default))
  )
  (wire (pts (xy 520.7 67.31) (xy 519.43 67.31))
    (stroke (width 0) (type default))
  )
  (wire (pts (xy 168.91 264.16) (xy 163.83 264.16))
    (stroke (width 0) (type default))
  )
  (wire (pts (xy 228.6 347.98) (xy 228.6 345.44))
    (stroke (width 0) (type default))
  )
  (wire (pts (xy 283.21 66.04) (xy 280.67 66.04))
    (stroke (width 0) (type default))
  )
  (wire (pts (xy 168.91 224.79) (xy 163.83 224.79))
    (stroke (width 0) (type default))
  )
  (wire (pts (xy 246.38 267.97) (xy 246.38 266.7))
    (stroke (width 0) (type default))
  )
  (wire (pts (xy 444.5 100.33) (xy 444.5 107.95))
    (stroke (width 0) (type default))
  )
  (wire (pts (xy 210.82 66.04) (xy 227.33 66.04))
    (stroke (width 0) (type default))
  )
  (wire (pts (xy 461.01 54.61) (xy 444.5 54.61))
    (stroke (width 0) (type default))
  )
  (wire (pts (xy 523.24 309.88) (xy 566.42 309.88))
    (stroke (width 0) (type default))
  )
  (wire (pts (xy 508 62.23) (xy 508 64.77))
    (stroke (width 0) (type default))
  )
  (wire (pts (xy 52.07 64.77) (xy 25.4 64.77))
    (stroke (width 0) (type default))
  )
  (wire (pts (xy 461.01 95.25) (xy 448.31 95.25))
    (stroke (width 0) (type default))
  )
  (wire (pts (xy 524.51 156.21) (xy 524.51 153.67))
    (stroke (width 0) (type default))
  )
  (wire (pts (xy 269.24 63.5) (xy 280.67 63.5))
    (stroke (width 0) (type default))
  )
  (wire (pts (xy 537.21 165.1) (xy 537.21 161.29))
    (stroke (width 0) (type default))
  )
  (wire (pts (xy 461.01 59.69) (xy 448.31 59.69))
    (stroke (width 0) (type default))
  )
  (wire (pts (xy 532.13 110.49) (xy 506.73 110.49))
    (stroke (width 0) (type default))
  )
  (bus (pts (xy 429.26 261.62) (xy 431.8 264.16))
    (stroke (width 0) (type default))
  )

  (wire (pts (xy 461.01 49.53) (xy 448.31 49.53))
    (stroke (width 0) (type default))
  )
  (wire (pts (xy 186.69 262.89) (xy 186.69 264.16))
    (stroke (width 0) (type default))
  )
  (wire (pts (xy 176.53 167.64) (xy 175.26 167.64))
    (stroke (width 0) (type default))
  )
  (wire (pts (xy 35.56 162.56) (xy 43.18 162.56))
    (stroke (width 0) (type default))
  )
  (wire (pts (xy 355.6 303.53) (xy 374.65 303.53))
    (stroke (width 0) (type default))
  )
  (wire (pts (xy 346.71 236.22) (xy 354.33 236.22))
    (stroke (width 0) (type default))
  )
  (wire (pts (xy 389.89 293.37) (xy 389.89 294.64))
    (stroke (width 0) (type default))
  )
  (wire (pts (xy 393.7 299.72) (xy 393.7 316.23))
    (stroke (width 0) (type default))
  )
  (wire (pts (xy 237.49 226.06) (xy 237.49 228.6))
    (stroke (width 0) (type default))
  )
  (wire (pts (xy 461.01 90.17) (xy 448.31 90.17))
    (stroke (width 0) (type default))
  )
  (wire (pts (xy 377.19 48.26) (xy 387.35 48.26))
    (stroke (width 0) (type default))
  )
  (wire (pts (xy 90.17 59.69) (xy 99.06 59.69))
    (stroke (width 0) (type default))
  )
  (wire (pts (xy 276.86 49.53) (xy 270.51 49.53))
    (stroke (width 0) (type default))
  )
  (wire (pts (xy 372.11 251.46) (xy 372.11 254))
    (stroke (width 0) (type default))
  )
  (wire (pts (xy 459.74 276.86) (xy 436.88 276.86))
    (stroke (width 0) (type default))
  )
  (wire (pts (xy 557.53 167.64) (xy 530.86 167.64))
    (stroke (width 0) (type default))
  )
  (wire (pts (xy 176.53 264.16) (xy 176.53 266.7))
    (stroke (width 0) (type default))
  )
  (wire (pts (xy 534.67 246.38) (xy 534.67 237.49))
    (stroke (width 0) (type default))
  )
  (bus (pts (xy 123.19 67.31) (xy 123.19 69.85))
    (stroke (width 0) (type default))
  )

  (wire (pts (xy 251.46 133.35) (xy 248.92 133.35))
    (stroke (width 0) (type default))
  )
  (bus (pts (xy 123.19 67.31) (xy 125.73 64.77))
    (stroke (width 0) (type default))
  )

  (wire (pts (xy 236.22 339.09) (xy 251.46 339.09))
    (stroke (width 0) (type default))
  )
  (wire (pts (xy 439.42 128.27) (xy 450.85 128.27))
    (stroke (width 0) (type default))
  )
  (wire (pts (xy 363.22 49.53) (xy 363.22 48.26))
    (stroke (width 0) (type default))
  )
  (wire (pts (xy 427.99 151.13) (xy 434.34 151.13))
    (stroke (width 0) (type default))
  )
  (wire (pts (xy 280.67 68.58) (xy 280.67 66.04))
    (stroke (width 0) (type default))
  )
  (wire (pts (xy 461.01 100.33) (xy 444.5 100.33))
    (stroke (width 0) (type default))
  )
  (wire (pts (xy 523.24 294.64) (xy 566.42 294.64))
    (stroke (width 0) (type default))
  )
  (wire (pts (xy 341.63 326.39) (xy 345.44 326.39))
    (stroke (width 0) (type default))
  )
  (wire (pts (xy 265.43 378.46) (xy 261.62 378.46))
    (stroke (width 0) (type default))
  )
  (wire (pts (xy 165.1 346.075) (xy 165.1 349.25))
    (stroke (width 0) (type default))
  )
  (wire (pts (xy 172.085 349.25) (xy 165.1 349.25))
    (stroke (width 0) (type default))
  )
  (wire (pts (xy 345.44 322.58) (xy 345.44 326.39))
    (stroke (width 0) (type default))
  )
  (wire (pts (xy 228.6 226.06) (xy 237.49 226.06))
    (stroke (width 0) (type default))
  )
  (wire (pts (xy 461.01 92.71) (xy 448.31 92.71))
    (stroke (width 0) (type default))
  )
  (wire (pts (xy 168.91 234.95) (xy 177.8 234.95))
    (stroke (width 0) (type default))
  )
  (wire (pts (xy 382.27 322.58) (xy 382.27 326.39))
    (stroke (width 0) (type default))
  )
  (wire (pts (xy 415.29 125.73) (xy 434.34 125.73))
    (stroke (width 0) (type default))
  )
  (wire (pts (xy 458.47 153.67) (xy 458.47 151.13))
    (stroke (width 0) (type default))
  )
  (wire (pts (xy 161.29 48.26) (xy 179.07 48.26))
    (stroke (width 0) (type default))
  )
  (wire (pts (xy 63.5 53.34) (xy 38.1 53.34))
    (stroke (width 0) (type default))
  )
  (wire (pts (xy 511.81 59.69) (xy 508 59.69))
    (stroke (width 0) (type default))
  )
  (wire (pts (xy 34.29 302.26) (xy 34.29 300.99))
    (stroke (width 0) (type default))
  )
  (wire (pts (xy 254 347.98) (xy 236.22 347.98))
    (stroke (width 0) (type default))
  )
  (wire (pts (xy 386.08 294.64) (xy 386.08 293.37))
    (stroke (width 0) (type default))
  )
  (wire (pts (xy 168.91 160.02) (xy 170.18 160.02))
    (stroke (width 0) (type default))
  )
  (wire (pts (xy 177.8 222.25) (xy 177.8 224.79))
    (stroke (width 0) (type default))
  )
  (wire (pts (xy 459.74 327.66) (xy 434.34 327.66))
    (stroke (width 0) (type default))
  )
  (wire (pts (xy 543.56 153.67) (xy 543.56 156.21))
    (stroke (width 0) (type default))
  )
  (wire (pts (xy 434.34 335.28) (xy 459.74 335.28))
    (stroke (width 0) (type default))
  )
  (wire (pts (xy 78.74 228.6) (xy 87.63 228.6))
    (stroke (width 0) (type default))
  )
  (wire (pts (xy 378.46 80.01) (xy 381 80.01))
    (stroke (width 0) (type default))
  )
  (wire (pts (xy 153.67 264.16) (xy 158.75 264.16))
    (stroke (width 0) (type default))
  )
  (wire (pts (xy 110.49 166.37) (xy 110.49 165.1))
    (stroke (width 0) (type default))
  )
  (wire (pts (xy 67.31 241.3) (xy 69.85 241.3))
    (stroke (width 0) (type default))
  )
  (wire (pts (xy 144.78 224.79) (xy 144.78 227.33))
    (stroke (width 0) (type default))
  )
  (wire (pts (xy 548.64 52.07) (xy 565.15 52.07))
    (stroke (width 0) (type default))
  )
  (polyline (pts (xy 12.7 189.23) (xy 581.66 189.23))
    (stroke (width 0) (type default))
  )

  (wire (pts (xy 228.6 266.7) (xy 228.6 267.97))
    (stroke (width 0) (type default))
  )
  (wire (pts (xy 259.08 140.97) (xy 259.08 133.35))
    (stroke (width 0) (type default))
  )
  (bus (pts (xy 123.19 87.63) (xy 123.19 90.17))
    (stroke (width 0) (type default))
  )

  (polyline (pts (xy 485.14 123.19) (xy 581.66 123.19))
    (stroke (width 0) (type default))
  )

  (wire (pts (xy 271.78 154.94) (xy 271.78 149.86))
    (stroke (width 0) (type default))
  )
  (wire (pts (xy 228.6 332.74) (xy 228.6 331.47))
    (stroke (width 0) (type default))
  )
  (wire (pts (xy 228.6 226.06) (xy 228.6 228.6))
    (stroke (width 0) (type default))
  )
  (wire (pts (xy 459.74 322.58) (xy 434.34 322.58))
    (stroke (width 0) (type default))
  )
  (wire (pts (xy 434.34 314.96) (xy 459.74 314.96))
    (stroke (width 0) (type default))
  )
  (wire (pts (xy 41.91 332.74) (xy 41.91 328.93))
    (stroke (width 0) (type default))
  )
  (wire (pts (xy 538.48 322.58) (xy 542.29 322.58))
    (stroke (width 0) (type default))
  )
  (wire (pts (xy 459.74 312.42) (xy 434.34 312.42))
    (stroke (width 0) (type default))
  )
  (wire (pts (xy 461.01 97.79) (xy 448.31 97.79))
    (stroke (width 0) (type default))
  )
  (wire (pts (xy 228.6 265.43) (xy 228.6 266.7))
    (stroke (width 0) (type default))
  )
  (wire (pts (xy 450.85 226.06) (xy 441.96 226.06))
    (stroke (width 0) (type default))
  )
  (wire (pts (xy 307.34 316.23) (xy 345.44 316.23))
    (stroke (width 0) (type default))
  )
  (wire (pts (xy 378.46 293.37) (xy 374.65 293.37))
    (stroke (width 0) (type default))
  )
  (wire (pts (xy 76.2 304.8) (xy 76.2 302.26))
    (stroke (width 0) (type default))
  )
  (wire (pts (xy 246.38 266.7) (xy 256.54 266.7))
    (stroke (width 0) (type default))
  )
  (wire (pts (xy 90.17 147.32) (xy 111.76 147.32))
    (stroke (width 0) (type default))
  )
  (wire (pts (xy 378.46 293.37) (xy 382.27 293.37))
    (stroke (width 0) (type default))
  )
  (wire (pts (xy 461.01 39.37) (xy 448.31 39.37))
    (stroke (width 0) (type default))
  )
  (wire (pts (xy 334.01 299.72) (xy 334.01 308.61))
    (stroke (width 0) (type default))
  )
  (wire (pts (xy 378.46 306.07) (xy 378.46 317.5))
    (stroke (width 0) (type default))
  )
  (polyline (pts (xy 11.43 107.95) (xy 354.33 107.95))
    (stroke (width 0) (type default))
  )

  (wire (pts (xy 280.67 63.5) (xy 283.21 63.5))
    (stroke (width 0) (type default))
  )
  (bus (pts (xy 431.8 294.64) (xy 431.8 297.18))
    (stroke (width 0) (type default))
  )

  (wire (pts (xy 538.48 325.12) (xy 551.18 325.12))
    (stroke (width 0) (type default))
  )
  (wire (pts (xy 363.22 48.26) (xy 363.22 35.56))
    (stroke (width 0) (type default))
  )
  (wire (pts (xy 144.78 234.95) (xy 144.78 236.22))
    (stroke (width 0) (type default))
  )
  (wire (pts (xy 377.19 35.56) (xy 387.35 35.56))
    (stroke (width 0) (type default))
  )
  (wire (pts (xy 106.68 158.75) (xy 111.76 158.75))
    (stroke (width 0) (type default))
  )
  (wire (pts (xy 417.83 243.84) (xy 417.83 241.3))
    (stroke (width 0) (type default))
  )
  (wire (pts (xy 326.39 293.37) (xy 326.39 294.64))
    (stroke (width 0) (type default))
  )
  (wire (pts (xy 162.56 153.67) (xy 162.56 152.4))
    (stroke (width 0) (type default))
  )
  (wire (pts (xy 439.42 125.73) (xy 453.39 125.73))
    (stroke (width 0) (type default))
  )
  (wire (pts (xy 228.6 266.7) (xy 237.49 266.7))
    (stroke (width 0) (type default))
  )
  (bus (pts (xy 431.8 264.16) (xy 431.8 276.86))
    (stroke (width 0) (type default))
  )

  (wire (pts (xy 177.8 137.16) (xy 175.26 137.16))
    (stroke (width 0) (type default))
  )
  (wire (pts (xy 264.16 154.94) (xy 259.08 154.94))
    (stroke (width 0) (type default))
  )
  (wire (pts (xy 360.68 384.81) (xy 363.22 384.81))
    (stroke (width 0) (type default))
  )
  (wire (pts (xy 461.01 115.57) (xy 448.31 115.57))
    (stroke (width 0) (type default))
  )
  (wire (pts (xy 427.99 241.3) (xy 450.85 241.3))
    (stroke (width 0) (type default))
  )
  (wire (pts (xy 346.71 222.25) (xy 354.33 222.25))
    (stroke (width 0) (type default))
  )
  (wire (pts (xy 439.42 130.81) (xy 453.39 130.81))
    (stroke (width 0) (type default))
  )
  (wire (pts (xy 269.24 154.94) (xy 271.78 154.94))
    (stroke (width 0) (type default))
  )
  (wire (pts (xy 63.5 87.63) (xy 39.37 87.63))
    (stroke (width 0) (type default))
  )
  (wire (pts (xy 87.63 228.6) (xy 87.63 226.06))
    (stroke (width 0) (type default))
  )
  (wire (pts (xy 63.5 80.01) (xy 39.37 80.01))
    (stroke (width 0) (type default))
  )
  (wire (pts (xy 542.29 105.41) (xy 567.69 105.41))
    (stroke (width 0) (type default))
  )
  (wire (pts (xy 523.24 271.78) (xy 566.42 271.78))
    (stroke (width 0) (type default))
  )
  (wire (pts (xy 228.6 259.08) (xy 228.6 260.35))
    (stroke (width 0) (type default))
  )
  (wire (pts (xy 523.24 279.4) (xy 566.42 279.4))
    (stroke (width 0) (type default))
  )
  (wire (pts (xy 63.5 90.17) (xy 39.37 90.17))
    (stroke (width 0) (type default))
  )
  (wire (pts (xy 523.24 342.9) (xy 537.21 342.9))
    (stroke (width 0) (type default))
  )
  (bus (pts (xy 123.19 72.39) (xy 123.19 74.93))
    (stroke (width 0) (type default))
  )

  (wire (pts (xy 459.74 261.62) (xy 445.77 261.62))
    (stroke (width 0) (type default))
  )
  (wire (pts (xy 175.26 303.53) (xy 175.26 300.99))
    (stroke (width 0) (type default))
  )
  (wire (pts (xy 548.64 49.53) (xy 565.15 49.53))
    (stroke (width 0) (type default))
  )
  (wire (pts (xy 57.15 328.93) (xy 49.53 328.93))
    (stroke (width 0) (type default))
  )
  (wire (pts (xy 370.84 80.01) (xy 373.38 80.01))
    (stroke (width 0) (type default))
  )
  (wire (pts (xy 261.62 378.46) (xy 261.62 382.27))
    (stroke (width 0) (type default))
  )
  (wire (pts (xy 444.5 77.47) (xy 444.5 100.33))
    (stroke (width 0) (type default))
  )
  (wire (pts (xy 210.82 63.5) (xy 227.33 63.5))
    (stroke (width 0) (type default))
  )
  (wire (pts (xy 427.99 148.59) (xy 427.99 151.13))
    (stroke (width 0) (type default))
  )
  (wire (pts (xy 434.34 289.56) (xy 459.74 289.56))
    (stroke (width 0) (type default))
  )
  (wire (pts (xy 265.43 267.97) (xy 265.43 266.7))
    (stroke (width 0) (type default))
  )
  (wire (pts (xy 528.32 241.3) (xy 528.32 237.49))
    (stroke (width 0) (type default))
  )
  (wire (pts (xy 538.48 284.48) (xy 542.29 284.48))
    (stroke (width 0) (type default))
  )
  (wire (pts (xy 210.82 58.42) (xy 227.33 58.42))
    (stroke (width 0) (type default))
  )
  (bus (pts (xy 123.19 69.85) (xy 123.19 72.39))
    (stroke (width 0) (type default))
  )

  (wire (pts (xy 36.83 228.6) (xy 49.53 228.6))
    (stroke (width 0) (type default))
  )
  (wire (pts (xy 334.01 322.58) (xy 334.01 326.39))
    (stroke (width 0) (type default))
  )
  (wire (pts (xy 168.91 266.7) (xy 168.91 264.16))
    (stroke (width 0) (type default))
  )
  (wire (pts (xy 461.01 44.45) (xy 448.31 44.45))
    (stroke (width 0) (type default))
  )
  (wire (pts (xy 256.54 273.05) (xy 256.54 274.32))
    (stroke (width 0) (type default))
  )
  (wire (pts (xy 459.74 251.46) (xy 433.07 251.46))
    (stroke (width 0) (type default))
  )
  (polyline (pts (xy 299.72 345.44) (xy 407.67 345.44))
    (stroke (width 0) (type default))
  )

  (wire (pts (xy 524.51 153.67) (xy 530.86 153.67))
    (stroke (width 0) (type default))
  )
  (wire (pts (xy 334.01 293.37) (xy 334.01 294.64))
    (stroke (width 0) (type default))
  )
  (wire (pts (xy 153.67 227.33) (xy 153.67 224.79))
    (stroke (width 0) (type default))
  )
  (wire (pts (xy 90.17 132.08) (xy 90.17 133.35))
    (stroke (width 0) (type default))
  )
  (wire (pts (xy 312.42 71.12) (xy 312.42 73.66))
    (stroke (width 0) (type default))
  )
  (wire (pts (xy 461.01 85.09) (xy 448.31 85.09))
    (stroke (width 0) (type default))
  )

  (text "RESET" (at 356.87 138.43 0)
    (effects (font (size 2.0066 2.0066) (thickness 0.4013) bold) (justify left bottom))
  )
  (text "Filtering" (at 316.23 119.38 0)
    (effects (font (size 1.4986 1.4986) (thickness 0.2997) bold) (justify left bottom))
  )
  (text "LED INDICATORS" (at 339.09 194.31 0)
    (effects (font (size 2.0066 2.0066) (thickness 0.4013) bold) (justify left bottom))
  )
  (text "DPHY0_D1_P" (at 538.48 266.7 0)
    (effects (font (size 1.27 1.27)) (justify right bottom))
  )
  (text "D18" (at 90.17 90.17 0)
    (effects (font (size 1.27 1.27)) (justify left bottom))
  )
  (text "DPHY0_D0_N" (at 537.21 264.16 0)
    (effects (font (size 1.27 1.27)) (justify right bottom))
  )
  (text "DPHY1_D1_N" (at 538.48 307.34 0)
    (effects (font (size 1.27 1.27)) (justify right bottom))
  )
  (text "Power supply " (at 13.97 195.58 0)
    (effects (font (size 2.9972 2.9972) (thickness 0.5994) bold) (justify left bottom))
  )
  (text "DPHY0_CLK_P" (at 538.48 256.54 0)
    (effects (font (size 1.27 1.27)) (justify right bottom))
  )
  (text "SDI output" (at 69.85 118.11 0)
    (effects (font (size 2.0066 2.0066) (thickness 0.4013) bold) (justify left bottom))
  )
  (text "D12" (at 90.17 74.93 0)
    (effects (font (size 1.27 1.27)) (justify left bottom))
  )
  (text "DPHY0_D3_N" (at 538.48 279.4 0)
    (effects (font (size 1.27 1.27)) (justify right bottom))
  )
  (text "Place close to GS2971A" (at 358.14 19.05 0)
    (effects (font (size 2.0066 2.0066) (thickness 0.4013) bold) (justify left bottom))
  )
  (text "SDI input" (at 226.06 119.38 0)
    (effects (font (size 2.0066 2.0066) (thickness 0.4013) bold) (justify left bottom))
  )
  (text "D15" (at 90.17 82.55 0)
    (effects (font (size 1.27 1.27)) (justify left bottom))
  )
  (text "D17" (at 90.17 87.63 0)
    (effects (font (size 1.27 1.27)) (justify left bottom))
  )
  (text "User button" (at 342.9 353.06 0)
    (effects (font (size 2.0066 2.0066) (thickness 0.4013) bold) (justify left bottom))
  )
  (text "DPHY0_D3_P" (at 538.48 276.86 0)
    (effects (font (size 1.27 1.27)) (justify right bottom))
  )
  (text "Power decoupling" (at 20.32 283.21 0)
    (effects (font (size 2.0066 2.0066) (thickness 0.4013) bold) (justify left bottom))
  )
  (text "D16" (at 90.17 85.09 0)
    (effects (font (size 1.27 1.27)) (justify left bottom))
  )
  (text "Used as RESET button by default" (at 336.55 355.6 0)
    (effects (font (size 1.27 1.27)) (justify left bottom))
  )
  (text "DPHY1_D3_P" (at 538.48 314.96 0)
    (effects (font (size 1.27 1.27)) (justify right bottom))
  )
  (text "DPHY0_D0_P" (at 537.21 261.62 0)
    (effects (font (size 1.27 1.27)) (justify right bottom))
  )
  (text "DPHY1_D2_N" (at 538.48 312.42 0)
    (effects (font (size 1.27 1.27)) (justify right bottom))
  )
  (text "SDI deserializer" (at 22.86 24.13 0)
    (effects (font (size 2.9972 2.9972) (thickness 0.5994) bold) (justify left bottom))
  )
  (text "DPHY1_CLK_P" (at 538.48 294.64 0)
    (effects (font (size 1.27 1.27)) (justify right bottom))
  )
  (text "I2S connector" (at 490.22 91.44 0)
    (effects (font (size 2.0066 2.0066) (thickness 0.4013) bold) (justify left bottom))
  )
  (text "Filtering" (at 358.14 60.96 0)
    (effects (font (size 1.27 1.27)) (justify left bottom))
  )
  (text "Logotypes" (at 12.7 180.34 0)
    (effects (font (size 2.0066 2.0066) (thickness 0.4013) bold) (justify left bottom))
  )
  (text "Low noise LDO\n" (at 15.24 201.93 0)
    (effects (font (size 2.0066 2.0066) (thickness 0.4013) bold) (justify left bottom))
  )
  (text "DPHY0_D2_P" (at 538.48 271.78 0)
    (effects (font (size 1.27 1.27)) (justify right bottom))
  )
  (text "Default configuration resistors" (at 330.2 278.13 0)
    (effects (font (size 2.0066 2.0066) (thickness 0.4013) bold) (justify left bottom))
  )
  (text "DPHY1_D3_N" (at 538.48 317.5 0)
    (effects (font (size 1.27 1.27)) (justify right bottom))
  )
  (text "DPHY1_CLK_N" (at 538.48 297.18 0)
    (effects (font (size 1.27 1.27)) (justify right bottom))
  )
  (text "Programming interace" (at 13.335 111.125 0)
    (effects (font (size 2.0066 2.0066) (thickness 0.4013) bold) (justify left bottom))
  )
  (text "DPHY1_D1_P" (at 538.48 304.8 0)
    (effects (font (size 1.27 1.27)) (justify right bottom))
  )
  (text "D14" (at 90.17 80.01 0)
    (effects (font (size 1.27 1.27)) (justify left bottom))
  )
  (text "GS Power Filtering" (at 123.19 203.2 0)
    (effects (font (size 2.0066 2.0066) (thickness 0.4013) bold) (justify left bottom))
  )
  (text "DNP if one I2C used" (at 501.65 158.75 0)
    (effects (font (size 1.27 1.27)) (justify left bottom))
  )
  (text "CrossLink Power Filtering" (at 213.36 201.93 0)
    (effects (font (size 2.0066 2.0066) (thickness 0.4013) bold) (justify left bottom))
  )
  (text "I2C to SPI bridge" (at 488.95 19.05 0)
    (effects (font (size 2.9972 2.9972) (thickness 0.5994) bold) (justify left bottom))
  )
  (text "DPHY1_D0_P" (at 538.48 299.72 0)
    (effects (font (size 1.27 1.27)) (justify right bottom))
  )
  (text "DPHY0_D1_N" (at 538.48 269.24 0)
    (effects (font (size 1.27 1.27)) (justify right bottom))
  )
  (text "D11" (at 90.17 72.39 0)
    (effects (font (size 1.27 1.27)) (justify left bottom))
  )
  (text "D13" (at 90.17 77.47 0)
    (effects (font (size 1.27 1.27)) (justify left bottom))
  )
  (text "DPHY1_D0_N" (at 538.48 302.26 0)
    (effects (font (size 1.27 1.27)) (justify right bottom))
  )
  (text "MIPI connector" (at 412.75 19.05 0)
    (effects (font (size 2.9972 2.9972) (thickness 0.5994) bold) (justify left bottom))
  )
  (text "GS_I2C" (at 12.7 146.05 0)
    (effects (font (size 2.0066 2.0066) (thickness 0.4013) bold) (justify left bottom))
  )
  (text "DPHY0_CLK_N" (at 538.48 259.08 0)
    (effects (font (size 1.27 1.27)) (justify right bottom))
  )
  (text "CrossLink and Semtech at same I2C Line" (at 410.21 120.65 0)
    (effects (font (size 0.9906 0.9906)) (justify left bottom))
  )
  (text "clock" (at 358.14 24.13 0)
    (effects (font (size 1.27 1.27)) (justify left bottom))
  )
  (text "DPHY0_D2_N" (at 538.48 274.32 0)
    (effects (font (size 1.27 1.27)) (justify right bottom))
  )
  (text "D10" (at 90.17 69.85 0)
    (effects (font (size 1.27 1.27)) (justify left bottom))
  )
  (text "D19" (at 90.17 92.71 0)
    (effects (font (size 1.27 1.27)) (justify left bottom))
  )
  (text "CrossLink MIPI transmitter" (at 427.99 203.2 0)
    (effects (font (size 2.9972 2.9972) (thickness 0.5994) bold) (justify left bottom))
  )
  (text "Pull-up resistors" (at 490.22 129.54 0)
    (effects (font (size 2.0066 2.0066) (thickness 0.4013) bold) (justify left bottom))
  )
  (text "DPHY1_D2_P" (at 538.48 309.88 0)
    (effects (font (size 1.27 1.27)) (justify right bottom))
  )

  (label "MIPI1_D3_P" (at 448.31 82.55 0) (fields_autoplaced)
    (effects (font (size 1.27 1.27)) (justify left bottom))
  )
  (label "MIPI0_D1_P" (at 566.42 266.7 180) (fields_autoplaced)
    (effects (font (size 1.27 1.27)) (justify right bottom))
  )
  (label "GNDGPLL" (at 293.37 372.11 180) (fields_autoplaced)
    (effects (font (size 1.27 1.27)) (justify right bottom))
  )
  (label "SCL_GS" (at 509.27 54.61 0) (fields_autoplaced)
    (effects (font (size 1.27 1.27)) (justify left bottom))
  )
  (label "D8" (at 90.17 64.77 0) (fields_autoplaced)
    (effects (font (size 1.27 1.27)) (justify left bottom))
  )
  (label "MIPI0_CLK_P" (at 566.42 256.54 180) (fields_autoplaced)
    (effects (font (size 1.27 1.27)) (justify right bottom))
  )
  (label "~{RC_BYP}" (at 355.6 311.15 0) (fields_autoplaced)
    (effects (font (size 1.27 1.27)) (justify left bottom))
  )
  (label "SCL_GS" (at 43.18 160.02 180) (fields_autoplaced)
    (effects (font (size 1.27 1.27)) (justify right bottom))
  )
  (label "H_HSYNC" (at 38.1 48.26 0) (fields_autoplaced)
    (effects (font (size 1.27 1.27)) (justify left bottom))
  )
  (label "MIPI0_D0_N" (at 566.42 264.16 180) (fields_autoplaced)
    (effects (font (size 1.27 1.27)) (justify right bottom))
  )
  (label "Audio_EN_~{DIS}" (at 227.33 55.88 180) (fields_autoplaced)
    (effects (font (size 1.27 1.27)) (justify right bottom))
  )
  (label "SDA_GS" (at 509.27 52.07 0) (fields_autoplaced)
    (effects (font (size 1.27 1.27)) (justify left bottom))
  )
  (label "DOUT11" (at 110.49 72.39 0) (fields_autoplaced)
    (effects (font (size 1.27 1.27)) (justify left bottom))
  )
  (label "GNDPLL_DPHY" (at 293.37 378.46 180) (fields_autoplaced)
    (effects (font (size 1.27 1.27)) (justify right bottom))
  )
  (label "AGCN" (at 394.97 113.03 180) (fields_autoplaced)
    (effects (font (size 1.27 1.27)) (justify right bottom))
  )
  (label "SPI_SS(SCL)" (at 415.29 128.27 0) (fields_autoplaced)
    (effects (font (size 1.27 1.27)) (justify left bottom))
  )
  (label "MIPI0_CLK_P" (at 448.31 59.69 0) (fields_autoplaced)
    (effects (font (size 1.27 1.27)) (justify left bottom))
  )
  (label "LOCKED_CL" (at 436.88 269.24 0) (fields_autoplaced)
    (effects (font (size 1.27 1.27)) (justify left bottom))
  )
  (label "MIPI0_D2_N" (at 566.42 274.32 180) (fields_autoplaced)
    (effects (font (size 1.27 1.27)) (justify right bottom))
  )
  (label "MIPI1_D2_N" (at 566.42 312.42 180) (fields_autoplaced)
    (effects (font (size 1.27 1.27)) (justify right bottom))
  )
  (label "DOUT10" (at 434.34 279.4 0) (fields_autoplaced)
    (effects (font (size 1.27 1.27)) (justify left bottom))
  )
  (label "PCLK" (at 38.1 44.45 0) (fields_autoplaced)
    (effects (font (size 1.27 1.27)) (justify left bottom))
  )
  (label "AUDIO_OUTPUT_CH3_4" (at 506.73 107.95 0) (fields_autoplaced)
    (effects (font (size 1.27 1.27)) (justify left bottom))
  )
  (label "USER_SDA" (at 58.42 119.38 180) (fields_autoplaced)
    (effects (font (size 1.27 1.27)) (justify right bottom))
  )
  (label "AUDIO_MASTER_CLK" (at 567.69 110.49 180) (fields_autoplaced)
    (effects (font (size 1.27 1.27)) (justify right bottom))
  )
  (label "CRESET_B" (at 58.42 127 180) (fields_autoplaced)
    (effects (font (size 1.27 1.27)) (justify right bottom))
  )
  (label "MIPI1_D2_P" (at 448.31 87.63 0) (fields_autoplaced)
    (effects (font (size 1.27 1.27)) (justify left bottom))
  )
  (label "SDA_GS" (at 557.53 162.56 180) (fields_autoplaced)
    (effects (font (size 1.27 1.27)) (justify right bottom))
  )
  (label "SDO_N" (at 39.37 90.17 0) (fields_autoplaced)
    (effects (font (size 1.27 1.27)) (justify left bottom))
  )
  (label "SDO_EN_DIS" (at 227.33 76.2 180) (fields_autoplaced)
    (effects (font (size 1.27 1.27)) (justify right bottom))
  )
  (label "DOUT11" (at 441.96 281.94 180) (fields_autoplaced)
    (effects (font (size 1.27 1.27)) (justify right bottom))
  )
  (label "SPI_SS(SCL)" (at 557.53 170.18 180) (fields_autoplaced)
    (effects (font (size 1.27 1.27)) (justify right bottom))
  )
  (label "MIPI1_D1_N" (at 566.42 307.34 180) (fields_autoplaced)
    (effects (font (size 1.27 1.27)) (justify right bottom))
  )
  (label "AUDIO_WORD_CLK" (at 25.4 64.77 0) (fields_autoplaced)
    (effects (font (size 1.27 1.27)) (justify left bottom))
  )
  (label "H_HSYNC" (at 436.88 271.78 0) (fields_autoplaced)
    (effects (font (size 1.27 1.27)) (justify left bottom))
  )
  (label "MIPI0_D1_P" (at 448.31 46.99 0) (fields_autoplaced)
    (effects (font (size 1.27 1.27)) (justify left bottom))
  )
  (label "MIPI0_D1_N" (at 448.31 44.45 0) (fields_autoplaced)
    (effects (font (size 1.27 1.27)) (justify left bottom))
  )
  (label "SDO_P" (at 90.17 147.32 0) (fields_autoplaced)
    (effects (font (size 1.27 1.27)) (justify left bottom))
  )
  (label "MIPI0_D3_P" (at 448.31 36.83 0) (fields_autoplaced)
    (effects (font (size 1.27 1.27)) (justify left bottom))
  )
  (label "DOUT15" (at 110.49 82.55 0) (fields_autoplaced)
    (effects (font (size 1.27 1.27)) (justify left bottom))
  )
  (label "MIPI0_D3_N" (at 566.42 279.4 180) (fields_autoplaced)
    (effects (font (size 1.27 1.27)) (justify right bottom))
  )
  (label "DOUT10" (at 110.49 69.85 0) (fields_autoplaced)
    (effects (font (size 1.27 1.27)) (justify left bottom))
  )
  (label "MISO" (at 433.07 259.08 0) (fields_autoplaced)
    (effects (font (size 1.27 1.27)) (justify left bottom))
  )
  (label "~{CS}_TMS" (at 227.33 58.42 180) (fields_autoplaced)
    (effects (font (size 1.27 1.27)) (justify right bottom))
  )
  (label "AUDIO_OUTPUT_CH5_6" (at 39.37 80.01 0) (fields_autoplaced)
    (effects (font (size 1.27 1.27)) (justify left bottom))
  )
  (label "MIPI1_D1_P" (at 448.31 92.71 0) (fields_autoplaced)
    (effects (font (size 1.27 1.27)) (justify left bottom))
  )
  (label "SDIN_TDI" (at 227.33 73.66 180) (fields_autoplaced)
    (effects (font (size 1.27 1.27)) (justify right bottom))
  )
  (label "~{CS}_TMS" (at 565.15 57.15 180) (fields_autoplaced)
    (effects (font (size 1.27 1.27)) (justify right bottom))
  )
  (label "SPI_SCK(SDA)" (at 415.29 135.89 0) (fields_autoplaced)
    (effects (font (size 1.27 1.27)) (justify left bottom))
  )
  (label "D3" (at 90.17 52.07 0) (fields_autoplaced)
    (effects (font (size 1.27 1.27)) (justify left bottom))
  )
  (label "IOPROC_EN_~{DIS}" (at 307.34 311.15 0) (fields_autoplaced)
    (effects (font (size 1.27 1.27)) (justify left bottom))
  )
  (label "~{DATA_ERROR}" (at 434.34 317.5 0) (fields_autoplaced)
    (effects (font (size 1.27 1.27)) (justify left bottom))
  )
  (label "SDO_P" (at 39.37 87.63 0) (fields_autoplaced)
    (effects (font (size 1.27 1.27)) (justify left bottom))
  )
  (label "LOCKED_CL" (at 326.39 215.9 0) (fields_autoplaced)
    (effects (font (size 1.27 1.27)) (justify left bottom))
  )
  (label "F_DE" (at 434.34 320.04 0) (fields_autoplaced)
    (effects (font (size 1.27 1.27)) (justify left bottom))
  )
  (label "AUDIO_WORD_CLK" (at 506.73 102.87 0) (fields_autoplaced)
    (effects (font (size 1.27 1.27)) (justify left bottom))
  )
  (label "~{RST_TRST_SOFT}" (at 401.32 163.83 180) (fields_autoplaced)
    (effects (font (size 1.27 1.27)) (justify right bottom))
  )
  (label "D0" (at 90.17 44.45 0) (fields_autoplaced)
    (effects (font (size 1.27 1.27)) (justify left bottom))
  )
  (label "MIPI0_CLK_N" (at 448.31 57.15 0) (fields_autoplaced)
    (effects (font (size 1.27 1.27)) (justify left bottom))
  )
  (label "SCL2" (at 459.74 138.43 180) (fields_autoplaced)
    (effects (font (size 1.27 1.27)) (justify right bottom))
  )
  (label "D9" (at 90.17 67.31 0) (fields_autoplaced)
    (effects (font (size 1.27 1.27)) (justify left bottom))
  )
  (label "MIPI0_D0_P" (at 448.31 52.07 0) (fields_autoplaced)
    (effects (font (size 1.27 1.27)) (justify left bottom))
  )
  (label "TIM_861" (at 227.33 83.82 180) (fields_autoplaced)
    (effects (font (size 1.27 1.27)) (justify right bottom))
  )
  (label "TIM_861" (at 355.6 308.61 0) (fields_autoplaced)
    (effects (font (size 1.27 1.27)) (justify left bottom))
  )
  (label "MIPI1_D2_N" (at 448.31 85.09 0) (fields_autoplaced)
    (effects (font (size 1.27 1.27)) (justify left bottom))
  )
  (label "DOUT14" (at 110.49 80.01 0) (fields_autoplaced)
    (effects (font (size 1.27 1.27)) (justify left bottom))
  )
  (label "SDOUT_TDO" (at 227.33 86.36 180) (fields_autoplaced)
    (effects (font (size 1.27 1.27)) (justify right bottom))
  )
  (label "SDA2" (at 459.74 135.89 180) (fields_autoplaced)
    (effects (font (size 1.27 1.27)) (justify right bottom))
  )
  (label "SDI_P" (at 284.48 146.05 180) (fields_autoplaced)
    (effects (font (size 1.27 1.27)) (justify right bottom))
  )
  (label "MISO" (at 17.78 127 0) (fields_autoplaced)
    (effects (font (size 1.27 1.27)) (justify left bottom))
  )
  (label "MIPI0_D0_P" (at 566.42 261.62 180) (fields_autoplaced)
    (effects (font (size 1.27 1.27)) (justify right bottom))
  )
  (label "LB_CONT" (at 161.29 48.26 0) (fields_autoplaced)
    (effects (font (size 1.27 1.27)) (justify left bottom))
  )
  (label "MIPI1_D3_N" (at 448.31 80.01 0) (fields_autoplaced)
    (effects (font (size 1.27 1.27)) (justify left bottom))
  )
  (label "Y_1ANC" (at 38.1 58.42 0) (fields_autoplaced)
    (effects (font (size 1.27 1.27)) (justify left bottom))
  )
  (label "MIPI1_D0_P" (at 448.31 97.79 0) (fields_autoplaced)
    (effects (font (size 1.27 1.27)) (justify left bottom))
  )
  (label "DVB_ASI" (at 434.34 347.98 0) (fields_autoplaced)
    (effects (font (size 1.27 1.27)) (justify left bottom))
  )
  (label "~{RST_TRST_SOFT}" (at 434.34 312.42 0) (fields_autoplaced)
    (effects (font (size 1.27 1.27)) (justify left bottom))
  )
  (label "RST" (at 449.58 115.57 0) (fields_autoplaced)
    (effects (font (size 1.27 1.27)) (justify left bottom))
  )
  (label "AUDIO_WORD_CLK" (at 567.69 102.87 180) (fields_autoplaced)
    (effects (font (size 1.27 1.27)) (justify right bottom))
  )
  (label "MIPI1_D3_N" (at 566.42 317.5 180) (fields_autoplaced)
    (effects (font (size 1.27 1.27)) (justify right bottom))
  )
  (label "STANDBY" (at 355.6 313.69 0) (fields_autoplaced)
    (effects (font (size 1.27 1.27)) (justify left bottom))
  )
  (label "MIPI0_D3_N" (at 448.31 34.29 0) (fields_autoplaced)
    (effects (font (size 1.27 1.27)) (justify left bottom))
  )
  (label "MOSI" (at 17.78 124.46 0) (fields_autoplaced)
    (effects (font (size 1.27 1.27)) (justify left bottom))
  )
  (label "AGCP" (at 161.29 71.12 0) (fields_autoplaced)
    (effects (font (size 1.27 1.27)) (justify left bottom))
  )
  (label "CRESET_B" (at 433.07 241.3 0) (fields_autoplaced)
    (effects (font (size 1.27 1.27)) (justify left bottom))
  )
  (label "D7" (at 90.17 62.23 0) (fields_autoplaced)
    (effects (font (size 1.27 1.27)) (justify left bottom))
  )
  (label "~{SMPTE_BYPASS}" (at 434.34 345.44 0) (fields_autoplaced)
    (effects (font (size 1.27 1.27)) (justify left bottom))
  )
  (label "GNDGPLL" (at 537.21 345.44 180) (fields_autoplaced)
    (effects (font (size 1.27 1.27)) (justify right bottom))
  )
  (label "SW_EN" (at 227.33 81.28 180) (fields_autoplaced)
    (effects (font (size 1.27 1.27)) (justify right bottom))
  )
  (label "DOUT[19..10]" (at 416.56 261.62 0) (fields_autoplaced)
    (effects (font (size 1.27 1.27)) (justify left bottom))
  )
  (label "GNDGPLL" (at 254 347.98 180) (fields_autoplaced)
    (effects (font (size 1.27 1.27)) (justify right bottom))
  )
  (label "20bit_~{10bit}" (at 434.34 342.9 0) (fields_autoplaced)
    (effects (font (size 1.27 1.27)) (justify left bottom))
  )
  (label "~{RST_TRST}" (at 227.33 68.58 180) (fields_autoplaced)
    (effects (font (size 1.27 1.27)) (justify right bottom))
  )
  (label "AUDIO_SERIAL_BIT_CLK" (at 567.69 100.33 180) (fields_autoplaced)
    (effects (font (size 1.27 1.27)) (justify right bottom))
  )
  (label "XTAL2" (at 387.35 35.56 180) (fields_autoplaced)
    (effects (font (size 1.27 1.27)) (justify right bottom))
  )
  (label "USER_LED" (at 434.34 340.36 0) (fields_autoplaced)
    (effects (font (size 1.27 1.27)) (justify left bottom))
  )
  (label "DOUT[19..10]" (at 127 64.77 0) (fields_autoplaced)
    (effects (font (size 1.27 1.27)) (justify left bottom))
  )
  (label "DOUT12" (at 110.49 74.93 0) (fields_autoplaced)
    (effects (font (size 1.27 1.27)) (justify left bottom))
  )
  (label "SCL1" (at 459.74 133.35 180) (fields_autoplaced)
    (effects (font (size 1.27 1.27)) (justify right bottom))
  )
  (label "LF" (at 161.29 50.8 0) (fields_autoplaced)
    (effects (font (size 1.27 1.27)) (justify left bottom))
  )
  (label "DOUT13" (at 441.96 287.02 180) (fields_autoplaced)
    (effects (font (size 1.27 1.27)) (justify right bottom))
  )
  (label "~{DATA_ERROR}" (at 328.93 251.46 0) (fields_autoplaced)
    (effects (font (size 1.27 1.27)) (justify left bottom))
  )
  (label "DOUT16" (at 110.49 85.09 0) (fields_autoplaced)
    (effects (font (size 1.27 1.27)) (justify left bottom))
  )
  (label "SDOUT_TDO" (at 565.15 46.99 180) (fields_autoplaced)
    (effects (font (size 1.27 1.27)) (justify right bottom))
  )
  (label "VBG" (at 161.29 53.34 0) (fields_autoplaced)
    (effects (font (size 1.27 1.27)) (justify left bottom))
  )
  (label "SDO_EN_DIS" (at 99.06 153.67 0) (fields_autoplaced)
    (effects (font (size 1.27 1.27)) (justify left bottom))
  )
  (label "USER_LED" (at 328.93 236.22 0) (fields_autoplaced)
    (effects (font (size 1.27 1.27)) (justify left bottom))
  )
  (label "DOUT18" (at 110.49 90.17 0) (fields_autoplaced)
    (effects (font (size 1.27 1.27)) (justify left bottom))
  )
  (label "SW_EN" (at 355.6 306.07 0) (fields_autoplaced)
    (effects (font (size 1.27 1.27)) (justify left bottom))
  )
  (label "D5" (at 90.17 57.15 0) (fields_autoplaced)
    (effects (font (size 1.27 1.27)) (justify left bottom))
  )
  (label "SCLK_TCK" (at 227.33 71.12 180) (fields_autoplaced)
    (effects (font (size 1.27 1.27)) (justify right bottom))
  )
  (label "DOUT16" (at 441.96 292.1 180) (fields_autoplaced)
    (effects (font (size 1.27 1.27)) (justify right bottom))
  )
  (label "DOUT12" (at 441.96 284.48 180) (fields_autoplaced)
    (effects (font (size 1.27 1.27)) (justify right bottom))
  )
  (label "DOUT14" (at 441.96 266.7 180) (fields_autoplaced)
    (effects (font (size 1.27 1.27)) (justify right bottom))
  )
  (label "MIPI1_CLK_N" (at 448.31 102.87 0) (fields_autoplaced)
    (effects (font (size 1.27 1.27)) (justify left bottom))
  )
  (label "~{DATA_ERROR}" (at 38.1 60.96 0) (fields_autoplaced)
    (effects (font (size 1.27 1.27)) (justify left bottom))
  )
  (label "XTAL1" (at 387.35 48.26 180) (fields_autoplaced)
    (effects (font (size 1.27 1.27)) (justify right bottom))
  )
  (label "V_VSYNC" (at 436.88 274.32 0) (fields_autoplaced)
    (effects (font (size 1.27 1.27)) (justify left bottom))
  )
  (label "USER_SW" (at 307.34 303.53 0) (fields_autoplaced)
    (effects (font (size 1.27 1.27)) (justify left bottom))
  )
  (label "VBG" (at 391.16 85.09 180) (fields_autoplaced)
    (effects (font (size 1.27 1.27)) (justify right bottom))
  )
  (label "SW_EN" (at 434.34 330.2 0) (fields_autoplaced)
    (effects (font (size 1.27 1.27)) (justify left bottom))
  )
  (label "D6" (at 90.17 59.69 0) (fields_autoplaced)
    (effects (font (size 1.27 1.27)) (justify left bottom))
  )
  (label "STANDBY" (at 434.34 314.96 0) (fields_autoplaced)
    (effects (font (size 1.27 1.27)) (justify left bottom))
  )
  (label "MIPI1_CLK_P" (at 448.31 105.41 0) (fields_autoplaced)
    (effects (font (size 1.27 1.27)) (justify left bottom))
  )
  (label "AUDIO_OUTPUT_CH1_2" (at 39.37 74.93 0) (fields_autoplaced)
    (effects (font (size 1.27 1.27)) (justify left bottom))
  )
  (label "MIPI1_D1_P" (at 566.42 304.8 180) (fields_autoplaced)
    (effects (font (size 1.27 1.27)) (justify right bottom))
  )
  (label "SPI_SCK(SDA)" (at 433.07 256.54 0) (fields_autoplaced)
    (effects (font (size 1.27 1.27)) (justify left bottom))
  )
  (label "LF" (at 391.16 88.9 180) (fields_autoplaced)
    (effects (font (size 1.27 1.27)) (justify right bottom))
  )
  (label "MIPI1_D0_P" (at 566.42 299.72 180) (fields_autoplaced)
    (effects (font (size 1.27 1.27)) (justify right bottom))
  )
  (label "DVB_ASI" (at 227.33 48.26 180) (fields_autoplaced)
    (effects (font (size 1.27 1.27)) (justify right bottom))
  )
  (label "IOPROC_EN_~{DIS}" (at 227.33 60.96 180) (fields_autoplaced)
    (effects (font (size 1.27 1.27)) (justify right bottom))
  )
  (label "SDO_EN_DIS" (at 307.34 306.07 0) (fields_autoplaced)
    (effects (font (size 1.27 1.27)) (justify left bottom))
  )
  (label "LB_CONT" (at 391.16 80.01 180) (fields_autoplaced)
    (effects (font (size 1.27 1.27)) (justify right bottom))
  )
  (label "~{RST_TRST}" (at 360.68 163.83 0) (fields_autoplaced)
    (effects (font (size 1.27 1.27)) (justify left bottom))
  )
  (label "SPI_SCK(SDA)" (at 557.53 167.64 180) (fields_autoplaced)
    (effects (font (size 1.27 1.27)) (justify right bottom))
  )
  (label "JTAG_~{HOST}" (at 355.6 316.23 0) (fields_autoplaced)
    (effects (font (size 1.27 1.27)) (justify left bottom))
  )
  (label "AUDIO_OUTPUT_CH3_4" (at 39.37 77.47 0) (fields_autoplaced)
    (effects (font (size 1.27 1.27)) (justify left bottom))
  )
  (label "DOUT18" (at 441.96 297.18 180) (fields_autoplaced)
    (effects (font (size 1.27 1.27)) (justify right bottom))
  )
  (label "USER_SCL" (at 433.07 248.92 0) (fields_autoplaced)
    (effects (font (size 1.27 1.27)) (justify left bottom))
  )
  (label "~{SMPTE_BYPASS}" (at 307.34 316.23 0) (fields_autoplaced)
    (effects (font (size 1.27 1.27)) (justify left bottom))
  )
  (label "Audio_EN_~{DIS}" (at 307.34 308.61 0) (fields_autoplaced)
    (effects (font (size 1.27 1.27)) (justify left bottom))
  )
  (label "AUDIO_OUTPUT_CH5_6" (at 567.69 105.41 180) (fields_autoplaced)
    (effects (font (size 1.27 1.27)) (justify right bottom))
  )
  (label "AUDIO_SERIAL_BIT_CLK" (at 25.4 67.31 0) (fields_autoplaced)
    (effects (font (size 1.27 1.27)) (justify left bottom))
  )
  (label "SPI_SS(SCL)" (at 415.29 138.43 0) (fields_autoplaced)
    (effects (font (size 1.27 1.27)) (justify left bottom))
  )
  (label "SCLK_TCK" (at 565.15 52.07 180) (fields_autoplaced)
    (effects (font (size 1.27 1.27)) (justify right bottom))
  )
  (label "D1" (at 90.17 46.99 0) (fields_autoplaced)
    (effects (font (size 1.27 1.27)) (justify left bottom))
  )
  (label "Audio_EN_~{DIS}" (at 434.34 335.28 0) (fields_autoplaced)
    (effects (font (size 1.27 1.27)) (justify left bottom))
  )
  (label "DOUT19" (at 110.49 92.71 0) (fields_autoplaced)
    (effects (font (size 1.27 1.27)) (justify left bottom))
  )
  (label "CDONE" (at 433.07 243.84 0) (fields_autoplaced)
    (effects (font (size 1.27 1.27)) (justify left bottom))
  )
  (label "LOCKED" (at 326.39 203.2 0) (fields_autoplaced)
    (effects (font (size 1.27 1.27)) (justify left bottom))
  )
  (label "USER_SW" (at 336.55 369.57 0) (fields_autoplaced)
    (effects (font (size 1.27 1.27)) (justify left bottom))
  )
  (label "Y_1ANC" (at 434.34 322.58 0) (fields_autoplaced)
    (effects (font (size 1.27 1.27)) (justify left bottom))
  )
  (label "SCL_GS" (at 557.53 165.1 180) (fields_autoplaced)
    (effects (font (size 1.27 1.27)) (justify right bottom))
  )
  (label "AUDIO_SERIAL_BIT_CLK" (at 506.73 100.33 0) (fields_autoplaced)
    (effects (font (size 1.27 1.27)) (justify left bottom))
  )
  (label "SPI_SCK(SDA)" (at 415.29 125.73 0) (fields_autoplaced)
    (effects (font (size 1.27 1.27)) (justify left bottom))
  )
  (label "MIPI0_D2_P" (at 448.31 41.91 0) (fields_autoplaced)
    (effects (font (size 1.27 1.27)) (justify left bottom))
  )
  (label "GNDPLL_DPHY" (at 288.29 274.32 180) (fields_autoplaced)
    (effects (font (size 1.27 1.27)) (justify right bottom))
  )
  (label "MIPI0_CLK_N" (at 566.42 259.08 180) (fields_autoplaced)
    (effects (font (size 1.27 1.27)) (justify right bottom))
  )
  (label "SPI_SCK(SDA)" (at 17.78 121.92 0) (fields_autoplaced)
    (effects (font (size 1.27 1.27)) (justify left bottom))
  )
  (label "MIPI1_CLK_N" (at 566.42 297.18 180) (fields_autoplaced)
    (effects (font (size 1.27 1.27)) (justify right bottom))
  )
  (label "GNDPLL_DPHY" (at 537.21 342.9 180) (fields_autoplaced)
    (effects (font (size 1.27 1.27)) (justify right bottom))
  )
  (label "SDA_GS" (at 43.18 157.48 180) (fields_autoplaced)
    (effects (font (size 1.27 1.27)) (justify right bottom))
  )
  (label "AUDIO_MASTER_CLK" (at 25.4 69.85 0) (fields_autoplaced)
    (effects (font (size 1.27 1.27)) (justify left bottom))
  )
  (label "TIM_861" (at 434.34 325.12 0) (fields_autoplaced)
    (effects (font (size 1.27 1.27)) (justify left bottom))
  )
  (label "D2" (at 90.17 49.53 0) (fields_autoplaced)
    (effects (font (size 1.27 1.27)) (justify left bottom))
  )
  (label "SDIN_TDI" (at 565.15 49.53 180) (fields_autoplaced)
    (effects (font (size 1.27 1.27)) (justify right bottom))
  )
  (label "V_VSYNC" (at 38.1 50.8 0) (fields_autoplaced)
    (effects (font (size 1.27 1.27)) (justify left bottom))
  )
  (label "SPI_SS(SCL)" (at 433.07 254 0) (fields_autoplaced)
    (effects (font (size 1.27 1.27)) (justify left bottom))
  )
  (label "SDO_N" (at 90.17 149.86 0) (fields_autoplaced)
    (effects (font (size 1.27 1.27)) (justify left bottom))
  )
  (label "AGCN" (at 161.29 73.66 0) (fields_autoplaced)
    (effects (font (size 1.27 1.27)) (justify left bottom))
  )
  (label "MIPI1_D0_N" (at 448.31 95.25 0) (fields_autoplaced)
    (effects (font (size 1.27 1.27)) (justify left bottom))
  )
  (label "MIPI0_D0_N" (at 448.31 49.53 0) (fields_autoplaced)
    (effects (font (size 1.27 1.27)) (justify left bottom))
  )
  (label "CDONE" (at 328.93 222.25 0) (fields_autoplaced)
    (effects (font (size 1.27 1.27)) (justify left bottom))
  )
  (label "STANDBY" (at 227.33 78.74 180) (fields_autoplaced)
    (effects (font (size 1.27 1.27)) (justify right bottom))
  )
  (label "SDI_N" (at 161.29 82.55 0) (fields_autoplaced)
    (effects (font (size 1.27 1.27)) (justify left bottom))
  )
  (label "MIPI1_D0_N" (at 566.42 302.26 180) (fields_autoplaced)
    (effects (font (size 1.27 1.27)) (justify right bottom))
  )
  (label "XTAL2" (at 161.29 60.96 0) (fields_autoplaced)
    (effects (font (size 1.27 1.27)) (justify left bottom))
  )
  (label "DVB_ASI" (at 355.6 303.53 0) (fields_autoplaced)
    (effects (font (size 1.27 1.27)) (justify left bottom))
  )
  (label "DOUT13" (at 110.49 77.47 0) (fields_autoplaced)
    (effects (font (size 1.27 1.27)) (justify left bottom))
  )
  (label "CRESET_B" (at 565.15 62.23 180) (fields_autoplaced)
    (effects (font (size 1.27 1.27)) (justify right bottom))
  )
  (label "USER_SCL" (at 58.42 121.92 180) (fields_autoplaced)
    (effects (font (size 1.27 1.27)) (justify right bottom))
  )
  (label "~{RC_BYP}" (at 434.34 327.66 0) (fields_autoplaced)
    (effects (font (size 1.27 1.27)) (justify left bottom))
  )
  (label "LOCKED" (at 38.1 55.88 0) (fields_autoplaced)
    (effects (font (size 1.27 1.27)) (justify left bottom))
  )
  (label "PCLK" (at 436.88 276.86 0) (fields_autoplaced)
    (effects (font (size 1.27 1.27)) (justify left bottom))
  )
  (label "MIPI1_CLK_P" (at 566.42 294.64 180) (fields_autoplaced)
    (effects (font (size 1.27 1.27)) (justify right bottom))
  )
  (label "20bit_~{10bit}" (at 307.34 313.69 0) (fields_autoplaced)
    (effects (font (size 1.27 1.27)) (justify left bottom))
  )
  (label "MIPI0_D2_N" (at 448.31 39.37 0) (fields_autoplaced)
    (effects (font (size 1.27 1.27)) (justify left bottom))
  )
  (label "MIPI0_D1_N" (at 566.42 269.24 180) (fields_autoplaced)
    (effects (font (size 1.27 1.27)) (justify right bottom))
  )
  (label "DOUT15" (at 441.96 289.56 180) (fields_autoplaced)
    (effects (font (size 1.27 1.27)) (justify right bottom))
  )
  (label "IOPROC_EN_~{DIS}" (at 434.34 332.74 0) (fields_autoplaced)
    (effects (font (size 1.27 1.27)) (justify left bottom))
  )
  (label "SPI_SS(SCL)" (at 17.78 129.54 0) (fields_autoplaced)
    (effects (font (size 1.27 1.27)) (justify left bottom))
  )
  (label "USER_SDA" (at 433.07 246.38 0) (fields_autoplaced)
    (effects (font (size 1.27 1.27)) (justify left bottom))
  )
  (label "F_DE" (at 38.1 53.34 0) (fields_autoplaced)
    (effects (font (size 1.27 1.27)) (justify left bottom))
  )
  (label "JTAG_~{HOST}" (at 434.34 309.88 0) (fields_autoplaced)
    (effects (font (size 1.27 1.27)) (justify left bottom))
  )
  (label "AUDIO_OUTPUT_CH1_2" (at 506.73 105.41 0) (fields_autoplaced)
    (effects (font (size 1.27 1.27)) (justify left bottom))
  )
  (label "AUDIO_OUTPUT_CH7_8" (at 39.37 82.55 0) (fields_autoplaced)
    (effects (font (size 1.27 1.27)) (justify left bottom))
  )
  (label "MIPI1_D1_N" (at 448.31 90.17 0) (fields_autoplaced)
    (effects (font (size 1.27 1.27)) (justify left bottom))
  )
  (label "MOSI" (at 433.07 251.46 0) (fields_autoplaced)
    (effects (font (size 1.27 1.27)) (justify left bottom))
  )
  (label "+3.3VA" (at 269.24 63.5 0) (fields_autoplaced)
    (effects (font (size 1.27 1.27)) (justify left bottom))
  )
  (label "SDI_P" (at 161.29 80.01 0) (fields_autoplaced)
    (effects (font (size 1.27 1.27)) (justify left bottom))
  )
  (label "JTAG_~{HOST}" (at 227.33 63.5 180) (fields_autoplaced)
    (effects (font (size 1.27 1.27)) (justify right bottom))
  )
  (label "MIPI0_D2_P" (at 566.42 271.78 180) (fields_autoplaced)
    (effects (font (size 1.27 1.27)) (justify right bottom))
  )
  (label "AGCP" (at 394.97 105.41 180) (fields_autoplaced)
    (effects (font (size 1.27 1.27)) (justify right bottom))
  )
  (label "MIPI1_D2_P" (at 566.42 309.88 180) (fields_autoplaced)
    (effects (font (size 1.27 1.27)) (justify right bottom))
  )
  (label "SDA_GS" (at 415.29 130.81 0) (fields_autoplaced)
    (effects (font (size 1.27 1.27)) (justify left bottom))
  )
  (label "USER_SW" (at 434.34 337.82 0) (fields_autoplaced)
    (effects (font (size 1.27 1.27)) (justify left bottom))
  )
  (label "AUDIO_OUTPUT_CH7_8" (at 567.69 107.95 180) (fields_autoplaced)
    (effects (font (size 1.27 1.27)) (justify right bottom))
  )
  (label "~{SMPTE_BYPASS}" (at 227.33 50.8 180) (fields_autoplaced)
    (effects (font (size 1.27 1.27)) (justify right bottom))
  )
  (label "DOUT17" (at 441.96 294.64 180) (fields_autoplaced)
    (effects (font (size 1.27 1.27)) (justify right bottom))
  )
  (label "DOUT19" (at 441.96 299.72 180) (fields_autoplaced)
    (effects (font (size 1.27 1.27)) (justify right bottom))
  )
  (label "SCL_GS" (at 415.29 133.35 0) (fields_autoplaced)
    (effects (font (size 1.27 1.27)) (justify left bottom))
  )
  (label "SDA1" (at 459.74 130.81 180) (fields_autoplaced)
    (effects (font (size 1.27 1.27)) (justify right bottom))
  )
  (label "D4" (at 90.17 54.61 0) (fields_autoplaced)
    (effects (font (size 1.27 1.27)) (justify left bottom))
  )
  (label "20bit_~{10bit}" (at 227.33 53.34 180) (fields_autoplaced)
    (effects (font (size 1.27 1.27)) (justify right bottom))
  )
  (label "SDI_N" (at 284.48 149.86 180) (fields_autoplaced)
    (effects (font (size 1.27 1.27)) (justify right bottom))
  )
  (label "DOUT17" (at 110.49 87.63 0) (fields_autoplaced)
    (effects (font (size 1.27 1.27)) (justify left bottom))
  )
  (label "XTAL1" (at 161.29 58.42 0) (fields_autoplaced)
    (effects (font (size 1.27 1.27)) (justify left bottom))
  )
  (label "MIPI1_D3_P" (at 566.42 314.96 180) (fields_autoplaced)
    (effects (font (size 1.27 1.27)) (justify right bottom))
  )
  (label "~{RC_BYP}" (at 227.33 66.04 180) (fields_autoplaced)
    (effects (font (size 1.27 1.27)) (justify right bottom))
  )
  (label "MIPI0_D3_P" (at 566.42 276.86 180) (fields_autoplaced)
    (effects (font (size 1.27 1.27)) (justify right bottom))
  )

  (global_label "IO_VDD" (shape input) (at 375.92 152.4 0) (fields_autoplaced)
    (effects (font (size 1.27 1.27)) (justify left))
    (property "Intersheetrefs" "${INTERSHEET_REFS}" (at 1.27 1.27 0)
      (effects (font (size 1.27 1.27)) hide)
    )
  )
  (global_label "VCCA_DPHY" (shape input) (at 552.45 322.58 0) (fields_autoplaced)
    (effects (font (size 1.27 1.27)) (justify left))
    (property "Intersheetrefs" "${INTERSHEET_REFS}" (at -5.08 5.08 0)
      (effects (font (size 1.27 1.27)) hide)
    )
  )
  (global_label "GNDREF" (shape input) (at 552.45 281.94 0) (fields_autoplaced)
    (effects (font (size 1.27 1.27)) (justify left))
    (property "Intersheetrefs" "${INTERSHEET_REFS}" (at -5.08 11.43 0)
      (effects (font (size 1.27 1.27)) hide)
    )
  )
  (global_label "VCCGPLL" (shape input) (at 254 339.09 0) (fields_autoplaced)
    (effects (font (size 1.27 1.27)) (justify left))
    (property "Intersheetrefs" "${INTERSHEET_REFS}" (at -24.13 -8.89 0)
      (effects (font (size 1.27 1.27)) hide)
    )
  )
  (global_label "VCC_IO" (shape input) (at 276.86 226.06 0) (fields_autoplaced)
    (effects (font (size 1.27 1.27)) (justify left))
    (property "Intersheetrefs" "${INTERSHEET_REFS}" (at -8.89 2.54 0)
      (effects (font (size 1.27 1.27)) hide)
    )
  )
  (global_label "VCC_IO" (shape input) (at 417.83 236.22 90) (fields_autoplaced)
    (effects (font (size 1.27 1.27)) (justify left))
    (property "Intersheetrefs" "${INTERSHEET_REFS}" (at 2.54 11.43 0)
      (effects (font (size 1.27 1.27)) hide)
    )
  )
  (global_label "IO_VDD" (shape input) (at 365.76 293.37 180) (fields_autoplaced)
    (effects (font (size 1.27 1.27)) (justify right))
    (property "Intersheetrefs" "${INTERSHEET_REFS}" (at 742.95 624.84 0)
      (effects (font (size 1.27 1.27)) hide)
    )
  )
  (global_label "IO_VDD" (shape input) (at 31.75 328.93 180) (fields_autoplaced)
    (effects (font (size 1.27 1.27)) (justify right))
    (property "Intersheetrefs" "${INTERSHEET_REFS}" (at -7.62 -10.16 0)
      (effects (font (size 1.27 1.27)) hide)
    )
  )
  (global_label "IO_VDD" (shape input) (at 317.5 293.37 180) (fields_autoplaced)
    (effects (font (size 1.27 1.27)) (justify right))
    (property "Intersheetrefs" "${INTERSHEET_REFS}" (at 694.69 624.84 0)
      (effects (font (size 1.27 1.27)) hide)
    )
  )
  (global_label "VCC_IO" (shape input) (at 445.77 302.26 180) (fields_autoplaced)
    (effects (font (size 1.27 1.27)) (justify right))
    (property "Intersheetrefs" "${INTERSHEET_REFS}" (at 17.78 6.35 0)
      (effects (font (size 1.27 1.27)) hide)
    )
  )
  (global_label "IO_VDD" (shape input) (at 172.085 349.25 0) (fields_autoplaced)
    (effects (font (size 1.27 1.27)) (justify left))
    (property "Intersheetrefs" "${INTERSHEET_REFS}" (at 9.525 -7.62 0)
      (effects (font (size 1.27 1.27)) hide)
    )
  )
  (global_label "IO_VDD" (shape input) (at 279.4 73.66 180) (fields_autoplaced)
    (effects (font (size 1.27 1.27)) (justify right))
    (property "Intersheetrefs" "${INTERSHEET_REFS}" (at 12.065 -13.97 0)
      (effects (font (size 1.27 1.27)) hide)
    )
  )
  (global_label "GNDREF" (shape input) (at 552.45 320.04 0) (fields_autoplaced)
    (effects (font (size 1.27 1.27)) (justify left))
    (property "Intersheetrefs" "${INTERSHEET_REFS}" (at -5.08 5.08 0)
      (effects (font (size 1.27 1.27)) hide)
    )
  )
  (global_label "VCO_VDD" (shape input) (at 270.51 49.53 180) (fields_autoplaced)
    (effects (font (size 1.27 1.27)) (justify right))
    (property "Intersheetrefs" "${INTERSHEET_REFS}" (at 1.905 21.59 0)
      (effects (font (size 1.27 1.27)) hide)
    )
  )
  (global_label "VCO_VDD" (shape input) (at 335.915 149.86 0) (fields_autoplaced)
    (effects (font (size 1.27 1.27)) (justify left))
    (property "Intersheetrefs" "${INTERSHEET_REFS}" (at 0.635 -3.81 0)
      (effects (font (size 1.27 1.27)) hide)
    )
  )
  (global_label "VCC_IO" (shape input) (at 445.77 261.62 180) (fields_autoplaced)
    (effects (font (size 1.27 1.27)) (justify right))
    (property "Intersheetrefs" "${INTERSHEET_REFS}" (at 19.05 11.43 0)
      (effects (font (size 1.27 1.27)) hide)
    )
  )
  (global_label "VCCA_DPHY" (shape input) (at 552.45 284.48 0) (fields_autoplaced)
    (effects (font (size 1.27 1.27)) (justify left))
    (property "Intersheetrefs" "${INTERSHEET_REFS}" (at -5.08 11.43 0)
      (effects (font (size 1.27 1.27)) hide)
    )
  )
  (global_label "VCC_IO" (shape input) (at 445.77 350.52 180) (fields_autoplaced)
    (effects (font (size 1.27 1.27)) (justify right))
    (property "Intersheetrefs" "${INTERSHEET_REFS}" (at 17.78 3.81 0)
      (effects (font (size 1.27 1.27)) hide)
    )
  )
  (global_label "VCCA_DPHY" (shape input) (at 275.59 266.7 0) (fields_autoplaced)
    (effects (font (size 1.27 1.27)) (justify left))
    (property "Intersheetrefs" "${INTERSHEET_REFS}" (at -3.81 0 0)
      (effects (font (size 1.27 1.27)) hide)
    )
  )
  (global_label "VCCGPLL" (shape input) (at 525.78 251.46 0) (fields_autoplaced)
    (effects (font (size 1.27 1.27)) (justify left))
    (property "Intersheetrefs" "${INTERSHEET_REFS}" (at -2.54 31.75 0)
      (effects (font (size 1.27 1.27)) hide)
    )
  )

  (symbol (lib_id "sdi-mipi-bridge:C_1u_0402") (at 264.16 140.97 0) (unit 1)
    (in_bom yes) (on_board yes) (dnp no)
    (property "Reference" "C55" (at 266.7 138.43 0)
      (effects (font (size 1.27 1.27)))
    )
    (property "Value" "C_1u_0402" (at 284.48 151.13 0)
      (effects (font (size 1.27 1.27) (thickness 0.15)) (justify left bottom) hide)
    )
    (property "Footprint" "sdi-mipi-bridge-footprints:C_0402_1005Metric" (at 284.48 153.67 0)
      (effects (font (size 1.27 1.27) (thickness 0.15)) (justify left bottom) hide)
    )
    (property "Datasheet" " " (at 284.48 156.21 0)
      (effects (font (size 1.27 1.27) (thickness 0.15)) (justify left bottom) hide)
    )
    (property "Manufacturer" "TDK" (at 284.48 161.29 0)
      (effects (font (size 1.27 1.27) (thickness 0.15)) (justify left bottom) hide)
    )
    (property "MPN" "C1005X6S1A105K050BC" (at 284.48 158.75 0)
      (effects (font (size 1.27 1.27) (thickness 0.15)) (justify left bottom) hide)
    )
    (property "Val" "1u" (at 266.7 143.51 0)
      (effects (font (size 1.27 1.27) (thickness 0.15)))
    )
    (property "License" "Apache-2.0" (at 284.48 163.83 0)
      (effects (font (size 1.27 1.27) (thickness 0.15)) (justify left bottom) hide)
    )
    (property "Author" "Antmicro" (at 284.48 166.37 0)
      (effects (font (size 1.27 1.27) (thickness 0.15)) (justify left bottom) hide)
    )
    (property "Voltage" "" (at 284.48 168.91 0)
      (effects (font (size 1.27 1.27)) (justify left bottom) hide)
    )
    (property "Dielectric" "" (at 284.48 171.45 0)
      (effects (font (size 1.27 1.27)) (justify left bottom) hide)
    )
    (pin "1")
    (pin "2")
    (instances
      (project "sdi-mipi-bridge"
        (path ""
          (reference "C55") (unit 1)
        )
      )
    )
  )

  (symbol (lib_id "sdi-mipi-bridge:C_1u_0402") (at 264.16 154.94 0) (unit 1)
    (in_bom yes) (on_board yes) (dnp no)
    (property "Reference" "C56" (at 266.7 152.4 0)
      (effects (font (size 1.27 1.27)))
    )
    (property "Value" "C_1u_0402" (at 284.48 165.1 0)
      (effects (font (size 1.27 1.27) (thickness 0.15)) (justify left bottom) hide)
    )
    (property "Footprint" "sdi-mipi-bridge-footprints:C_0402_1005Metric" (at 284.48 167.64 0)
      (effects (font (size 1.27 1.27) (thickness 0.15)) (justify left bottom) hide)
    )
    (property "Datasheet" " " (at 284.48 170.18 0)
      (effects (font (size 1.27 1.27) (thickness 0.15)) (justify left bottom) hide)
    )
    (property "Manufacturer" "TDK" (at 284.48 175.26 0)
      (effects (font (size 1.27 1.27) (thickness 0.15)) (justify left bottom) hide)
    )
    (property "MPN" "C1005X6S1A105K050BC" (at 284.48 172.72 0)
      (effects (font (size 1.27 1.27) (thickness 0.15)) (justify left bottom) hide)
    )
    (property "Val" "1u" (at 266.7 157.48 0)
      (effects (font (size 1.27 1.27) (thickness 0.15)))
    )
    (property "License" "Apache-2.0" (at 284.48 177.8 0)
      (effects (font (size 1.27 1.27) (thickness 0.15)) (justify left bottom) hide)
    )
    (property "Author" "Antmicro" (at 284.48 180.34 0)
      (effects (font (size 1.27 1.27) (thickness 0.15)) (justify left bottom) hide)
    )
    (property "Voltage" "" (at 284.48 182.88 0)
      (effects (font (size 1.27 1.27)) (justify left bottom) hide)
    )
    (property "Dielectric" "" (at 284.48 185.42 0)
      (effects (font (size 1.27 1.27)) (justify left bottom) hide)
    )
    (pin "1")
    (pin "2")
    (instances
      (project "sdi-mipi-bridge"
        (path ""
          (reference "C56") (unit 1)
        )
      )
    )
  )

  (symbol (lib_id "sdi-mipi-bridge:+1V2") (at 275.59 69.85 0) (unit 1)
    (in_bom yes) (on_board yes) (dnp no)
    (property "Reference" "#PWR049" (at 275.59 73.66 0)
      (effects (font (size 1.27 1.27)) hide)
    )
    (property "Value" "+1V2" (at 275.971 65.4558 0)
      (effects (font (size 1.27 1.27)))
    )
    (property "Footprint" "" (at 275.59 69.85 0)
      (effects (font (size 1.27 1.27)) hide)
    )
    (property "Datasheet" "" (at 275.59 69.85 0)
      (effects (font (size 1.27 1.27)) hide)
    )
    (pin "1")
    (instances
      (project "sdi-mipi-bridge"
        (path ""
          (reference "#PWR049") (unit 1)
        )
      )
    )
  )

  (symbol (lib_id "sdi-mipi-bridge:GNDA") (at 318.77 74.93 0) (unit 1)
    (in_bom yes) (on_board yes) (dnp no)
    (property "Reference" "#PWR054" (at 318.77 81.28 0)
      (effects (font (size 1.27 1.27)) hide)
    )
    (property "Value" "GNDA" (at 318.897 79.3242 0)
      (effects (font (size 1.27 1.27)))
    )
    (property "Footprint" "" (at 318.77 74.93 0)
      (effects (font (size 1.27 1.27)) hide)
    )
    (property "Datasheet" "" (at 318.77 74.93 0)
      (effects (font (size 1.27 1.27)) hide)
    )
    (pin "1")
    (instances
      (project "sdi-mipi-bridge"
        (path ""
          (reference "#PWR054") (unit 1)
        )
      )
    )
  )

  (symbol (lib_id "sdi-mipi-bridge:TP_1mm_SMD") (at 38.1 48.26 180) (unit 1)
    (in_bom yes) (on_board yes) (dnp no)
    (property "Reference" "TP1" (at 33.02 48.26 0)
      (effects (font (size 1.27 1.27)) (justify left))
    )
    (property "Value" "TP_1mm_SMD" (at 38.1 45.72 0)
      (effects (font (size 1.27 1.27) (thickness 0.15)) (justify left bottom) hide)
    )
    (property "Footprint" "sdi-mipi-bridge-footprints:Testpoint_smd_1mm" (at 33.02 53.34 0)
      (effects (font (size 1.27 1.27) (thickness 0.15)) (justify left bottom) hide)
    )
    (property "Datasheet" "" (at 33.02 55.88 0)
      (effects (font (size 1.27 1.27) (thickness 0.15)) (justify left bottom) hide)
    )
    (property "MPN" "" (at 38.1 48.26 0)
      (effects (font (size 1.27 1.27)) hide)
    )
    (property "Manufacturer" "" (at 38.1 48.26 0)
      (effects (font (size 1.27 1.27)) hide)
    )
    (property "Author" "Antmicro" (at 22.86 33.02 0)
      (effects (font (size 1.27 1.27) (thickness 0.15)) (justify left bottom) hide)
    )
    (property "License" "Apache-2.0" (at 22.86 30.48 0)
      (effects (font (size 1.27 1.27) (thickness 0.15)) (justify left bottom) hide)
    )
    (pin "1")
    (instances
      (project "sdi-mipi-bridge"
        (path ""
          (reference "TP1") (unit 1)
        )
      )
    )
  )

  (symbol (lib_id "sdi-mipi-bridge:TP_1mm_SMD") (at 38.1 50.8 180) (unit 1)
    (in_bom yes) (on_board yes) (dnp no)
    (property "Reference" "TP2" (at 33.02 50.7999 0)
      (effects (font (size 1.27 1.27)) (justify left))
    )
    (property "Value" "TP_1mm_SMD" (at 38.1 48.26 0)
      (effects (font (size 1.27 1.27) (thickness 0.15)) (justify left bottom) hide)
    )
    (property "Footprint" "sdi-mipi-bridge-footprints:Testpoint_smd_1mm" (at 33.02 55.88 0)
      (effects (font (size 1.27 1.27) (thickness 0.15)) (justify left bottom) hide)
    )
    (property "Datasheet" "" (at 33.02 58.42 0)
      (effects (font (size 1.27 1.27) (thickness 0.15)) (justify left bottom) hide)
    )
    (property "MPN" "" (at 38.1 50.8 0)
      (effects (font (size 1.27 1.27)) hide)
    )
    (property "Manufacturer" "" (at 38.1 50.8 0)
      (effects (font (size 1.27 1.27)) hide)
    )
    (property "Author" "Antmicro" (at 22.86 35.56 0)
      (effects (font (size 1.27 1.27) (thickness 0.15)) (justify left bottom) hide)
    )
    (property "License" "Apache-2.0" (at 22.86 33.02 0)
      (effects (font (size 1.27 1.27) (thickness 0.15)) (justify left bottom) hide)
    )
    (pin "1")
    (instances
      (project "sdi-mipi-bridge"
        (path ""
          (reference "TP2") (unit 1)
        )
      )
    )
  )

  (symbol (lib_id "sdi-mipi-bridge:C_470n_0402") (at 381 111.76 90) (unit 1)
    (in_bom yes) (on_board yes) (dnp no) (fields_autoplaced)
    (property "Reference" "C64" (at 383.54 107.9435 90)
      (effects (font (size 1.27 1.27)) (justify right))
    )
    (property "Value" "C_470n_0402" (at 391.16 91.44 0)
      (effects (font (size 1.27 1.27) (thickness 0.15)) (justify left bottom) hide)
    )
    (property "Footprint" "sdi-mipi-bridge-footprints:C_0402_1005Metric" (at 393.7 91.44 0)
      (effects (font (size 1.27 1.27) (thickness 0.15)) (justify left bottom) hide)
    )
    (property "Datasheet" " " (at 396.24 91.44 0)
      (effects (font (size 1.27 1.27) (thickness 0.15)) (justify left bottom) hide)
    )
    (property "Manufacturer" "TDK" (at 401.32 91.44 0)
      (effects (font (size 1.27 1.27) (thickness 0.15)) (justify left bottom) hide)
    )
    (property "MPN" "C1005X5R1E474M050BB" (at 398.78 91.44 0)
      (effects (font (size 1.27 1.27) (thickness 0.15)) (justify left bottom) hide)
    )
    (property "Val" "470n" (at 383.54 110.4835 90)
      (effects (font (size 1.27 1.27) (thickness 0.15)) (justify right))
    )
    (property "License" "Apache-2.0" (at 403.86 91.44 0)
      (effects (font (size 1.27 1.27) (thickness 0.15)) (justify left bottom) hide)
    )
    (property "Author" "Antmicro" (at 406.4 91.44 0)
      (effects (font (size 1.27 1.27) (thickness 0.15)) (justify left bottom) hide)
    )
    (property "Voltage" "" (at 408.94 91.44 0)
      (effects (font (size 1.27 1.27)) (justify left bottom) hide)
    )
    (property "Dielectric" "" (at 411.48 91.44 0)
      (effects (font (size 1.27 1.27)) (justify left bottom) hide)
    )
    (pin "1")
    (pin "2")
    (instances
      (project "sdi-mipi-bridge"
        (path ""
          (reference "C64") (unit 1)
        )
      )
    )
  )

  (symbol (lib_id "sdi-mipi-bridge:C_470n_0402") (at 377.19 113.03 180) (unit 1)
    (in_bom yes) (on_board yes) (dnp no)
    (property "Reference" "C61" (at 374.65 110.49 0)
      (effects (font (size 1.27 1.27)))
    )
    (property "Value" "C_470n_0402" (at 356.87 102.87 0)
      (effects (font (size 1.27 1.27) (thickness 0.15)) (justify left bottom) hide)
    )
    (property "Footprint" "sdi-mipi-bridge-footprints:C_0402_1005Metric" (at 356.87 100.33 0)
      (effects (font (size 1.27 1.27) (thickness 0.15)) (justify left bottom) hide)
    )
    (property "Datasheet" " " (at 356.87 97.79 0)
      (effects (font (size 1.27 1.27) (thickness 0.15)) (justify left bottom) hide)
    )
    (property "Manufacturer" "TDK" (at 356.87 92.71 0)
      (effects (font (size 1.27 1.27) (thickness 0.15)) (justify left bottom) hide)
    )
    (property "MPN" "C1005X5R1E474M050BB" (at 356.87 95.25 0)
      (effects (font (size 1.27 1.27) (thickness 0.15)) (justify left bottom) hide)
    )
    (property "Val" "470n" (at 374.65 115.57 0)
      (effects (font (size 1.27 1.27) (thickness 0.15)))
    )
    (property "License" "Apache-2.0" (at 356.87 90.17 0)
      (effects (font (size 1.27 1.27) (thickness 0.15)) (justify left bottom) hide)
    )
    (property "Author" "Antmicro" (at 356.87 87.63 0)
      (effects (font (size 1.27 1.27) (thickness 0.15)) (justify left bottom) hide)
    )
    (property "Voltage" "" (at 356.87 85.09 0)
      (effects (font (size 1.27 1.27)) (justify left bottom) hide)
    )
    (property "Dielectric" "" (at 356.87 82.55 0)
      (effects (font (size 1.27 1.27)) (justify left bottom) hide)
    )
    (pin "1")
    (pin "2")
    (instances
      (project "sdi-mipi-bridge"
        (path ""
          (reference "C61") (unit 1)
        )
      )
    )
  )

  (symbol (lib_id "sdi-mipi-bridge:GNDA") (at 369.57 114.3 0) (unit 1)
    (in_bom yes) (on_board yes) (dnp no)
    (property "Reference" "#PWR058" (at 369.57 120.65 0)
      (effects (font (size 1.27 1.27)) hide)
    )
    (property "Value" "GNDA" (at 369.697 118.6942 0)
      (effects (font (size 1.27 1.27)))
    )
    (property "Footprint" "" (at 369.57 114.3 0)
      (effects (font (size 1.27 1.27)) hide)
    )
    (property "Datasheet" "" (at 369.57 114.3 0)
      (effects (font (size 1.27 1.27)) hide)
    )
    (pin "1")
    (instances
      (project "sdi-mipi-bridge"
        (path ""
          (reference "#PWR058") (unit 1)
        )
      )
    )
  )

  (symbol (lib_id "sdi-mipi-bridge:TP_1mm_SMD") (at 176.53 63.5 180) (unit 1)
    (in_bom yes) (on_board yes) (dnp no) (fields_autoplaced)
    (property "Reference" "TP17" (at 171.45 63.4999 0)
      (effects (font (size 1.27 1.27)) (justify left))
    )
    (property "Value" "TP_1mm_SMD" (at 161.29 55.88 0)
      (effects (font (size 1.27 1.27) (thickness 0.15)) (justify left bottom) hide)
    )
    (property "Footprint" "sdi-mipi-bridge-footprints:Testpoint_smd_1mm" (at 161.29 53.34 0)
      (effects (font (size 1.27 1.27) (thickness 0.15)) (justify left bottom) hide)
    )
    (property "Datasheet" "" (at 161.29 50.8 0)
      (effects (font (size 1.27 1.27) (thickness 0.15)) (justify left bottom) hide)
    )
    (property "MPN" "" (at 176.53 63.5 0)
      (effects (font (size 1.27 1.27)) hide)
    )
    (property "Manufacturer" "" (at 176.53 63.5 0)
      (effects (font (size 1.27 1.27)) hide)
    )
    (property "Author" "Antmicro" (at 161.29 48.26 0)
      (effects (font (size 1.27 1.27) (thickness 0.15)) (justify left bottom) hide)
    )
    (property "License" "Apache-2.0" (at 161.29 45.72 0)
      (effects (font (size 1.27 1.27) (thickness 0.15)) (justify left bottom) hide)
    )
    (pin "1")
    (instances
      (project "sdi-mipi-bridge"
        (path ""
          (reference "TP17") (unit 1)
        )
      )
    )
  )

  (symbol (lib_id "sdi-mipi-bridge:Oscillator_SMD_27MHz_ABM7") (at 377.19 38.1 270) (unit 1)
    (in_bom yes) (on_board yes) (dnp no) (fields_autoplaced)
    (property "Reference" "Y1" (at 381 40.6399 90)
      (effects (font (size 1.27 1.27)) (justify left))
    )
    (property "Value" "Oscillator_SMD_27MHz_ABM7" (at 381 43.1799 90)
      (effects (font (size 1.27 1.27) (thickness 0.15)) (justify left) hide)
    )
    (property "Footprint" "sdi-mipi-bridge-footprints:Oscillator_SMD_Abracon_ABM7-2Pin_6x3.5mm" (at 367.03 59.69 0)
      (effects (font (size 1.27 1.27) (thickness 0.15)) (justify left bottom) hide)
    )
    (property "Datasheet" "http://www.farnell.com/datasheets/947971.pdf?_ga=2.27685436.1014497200.1574067480-156563690.1566371002&_gac=1.52917722.1572875319.Cj0KCQiAtf_tBRDtARIsAIbAKe0A1M5y_jdFCiNLNrHM5L2GjmDvn_4qnRvhHAD9jBdL9AmoMNThLCoaAjhJEALw_wcB" (at 364.49 59.69 0)
      (effects (font (size 1.27 1.27) (thickness 0.15)) (justify left bottom) hide)
    )
    (property "MPN" "ABM7-27.000MHZ-D2Y-T" (at 381 43.1799 90)
      (effects (font (size 1.27 1.27) (thickness 0.15)) (justify left))
    )
    (property "Manufacturer" "Abracon" (at 359.41 59.69 0)
      (effects (font (size 1.27 1.27) (thickness 0.15)) (justify left bottom) hide)
    )
    (property "Author" "Antmicro" (at 356.87 59.69 0)
      (effects (font (size 1.27 1.27) (thickness 0.15)) (justify left bottom) hide)
    )
    (property "License" "Apache-2.0" (at 354.33 59.69 0)
      (effects (font (size 1.27 1.27) (thickness 0.15)) (justify left bottom) hide)
    )
    (pin "1")
    (pin "2")
    (instances
      (project "sdi-mipi-bridge"
        (path ""
          (reference "Y1") (unit 1)
        )
      )
    )
  )

  (symbol (lib_id "sdi-mipi-bridge:GNDREF") (at 363.22 49.53 0) (unit 1)
    (in_bom yes) (on_board yes) (dnp no)
    (property "Reference" "#PWR056" (at 363.22 55.88 0)
      (effects (font (size 1.27 1.27)) hide)
    )
    (property "Value" "GNDREF" (at 363.22 53.34 0)
      (effects (font (size 1.27 1.27)))
    )
    (property "Footprint" "" (at 363.22 49.53 0)
      (effects (font (size 1.27 1.27)) hide)
    )
    (property "Datasheet" "" (at 363.22 49.53 0)
      (effects (font (size 1.27 1.27)) hide)
    )
    (pin "1")
    (instances
      (project "sdi-mipi-bridge"
        (path ""
          (reference "#PWR056") (unit 1)
        )
      )
    )
  )

  (symbol (lib_id "sdi-mipi-bridge:C_16p_0402") (at 369.57 35.56 0) (unit 1)
    (in_bom yes) (on_board yes) (dnp no) (fields_autoplaced)
    (property "Reference" "C59" (at 372.1163 29.21 0)
      (effects (font (size 1.27 1.27)))
    )
    (property "Value" "C_16p_0402" (at 389.89 45.72 0)
      (effects (font (size 1.27 1.27) (thickness 0.15)) (justify left bottom) hide)
    )
    (property "Footprint" "sdi-mipi-bridge-footprints:C_0402_1005Metric" (at 389.89 48.26 0)
      (effects (font (size 1.27 1.27) (thickness 0.15)) (justify left bottom) hide)
    )
    (property "Datasheet" " " (at 389.89 50.8 0)
      (effects (font (size 1.27 1.27) (thickness 0.15)) (justify left bottom) hide)
    )
    (property "Manufacturer" "Walsin" (at 389.89 55.88 0)
      (effects (font (size 1.27 1.27) (thickness 0.15)) (justify left bottom) hide)
    )
    (property "MPN" "0402N160J500CT" (at 389.89 53.34 0)
      (effects (font (size 1.27 1.27) (thickness 0.15)) (justify left bottom) hide)
    )
    (property "Val" "16p" (at 372.1163 31.75 0)
      (effects (font (size 1.27 1.27) (thickness 0.15)))
    )
    (property "License" "Apache-2.0" (at 389.89 58.42 0)
      (effects (font (size 1.27 1.27) (thickness 0.15)) (justify left bottom) hide)
    )
    (property "Author" "Antmicro" (at 389.89 60.96 0)
      (effects (font (size 1.27 1.27) (thickness 0.15)) (justify left bottom) hide)
    )
    (property "Voltage" "" (at 389.89 63.5 0)
      (effects (font (size 1.27 1.27)) (justify left bottom) hide)
    )
    (property "Dielectric" "" (at 389.89 66.04 0)
      (effects (font (size 1.27 1.27)) (justify left bottom) hide)
    )
    (pin "1")
    (pin "2")
    (instances
      (project "sdi-mipi-bridge"
        (path ""
          (reference "C59") (unit 1)
        )
      )
    )
  )

  (symbol (lib_id "sdi-mipi-bridge:C_16p_0402") (at 369.57 48.26 0) (unit 1)
    (in_bom yes) (on_board yes) (dnp no) (fields_autoplaced)
    (property "Reference" "C60" (at 372.1163 41.91 0)
      (effects (font (size 1.27 1.27)))
    )
    (property "Value" "C_16p_0402" (at 389.89 58.42 0)
      (effects (font (size 1.27 1.27) (thickness 0.15)) (justify left bottom) hide)
    )
    (property "Footprint" "sdi-mipi-bridge-footprints:C_0402_1005Metric" (at 389.89 60.96 0)
      (effects (font (size 1.27 1.27) (thickness 0.15)) (justify left bottom) hide)
    )
    (property "Datasheet" " " (at 389.89 63.5 0)
      (effects (font (size 1.27 1.27) (thickness 0.15)) (justify left bottom) hide)
    )
    (property "Manufacturer" "Walsin" (at 389.89 68.58 0)
      (effects (font (size 1.27 1.27) (thickness 0.15)) (justify left bottom) hide)
    )
    (property "MPN" "0402N160J500CT" (at 389.89 66.04 0)
      (effects (font (size 1.27 1.27) (thickness 0.15)) (justify left bottom) hide)
    )
    (property "Val" "16p" (at 372.1163 44.45 0)
      (effects (font (size 1.27 1.27) (thickness 0.15)))
    )
    (property "License" "Apache-2.0" (at 389.89 71.12 0)
      (effects (font (size 1.27 1.27) (thickness 0.15)) (justify left bottom) hide)
    )
    (property "Author" "Antmicro" (at 389.89 73.66 0)
      (effects (font (size 1.27 1.27) (thickness 0.15)) (justify left bottom) hide)
    )
    (property "Voltage" "" (at 389.89 76.2 0)
      (effects (font (size 1.27 1.27)) (justify left bottom) hide)
    )
    (property "Dielectric" "" (at 389.89 78.74 0)
      (effects (font (size 1.27 1.27)) (justify left bottom) hide)
    )
    (pin "1")
    (pin "2")
    (instances
      (project "sdi-mipi-bridge"
        (path ""
          (reference "C60") (unit 1)
        )
      )
    )
  )

  (symbol (lib_id "sdi-mipi-bridge:C_1u_0402") (at 378.46 85.09 180) (unit 1)
    (in_bom yes) (on_board yes) (dnp no)
    (property "Reference" "C62" (at 373.38 83.82 0)
      (effects (font (size 1.27 1.27)))
    )
    (property "Value" "C_1u_0402" (at 358.14 74.93 0)
      (effects (font (size 1.27 1.27) (thickness 0.15)) (justify left bottom) hide)
    )
    (property "Footprint" "sdi-mipi-bridge-footprints:C_0402_1005Metric" (at 358.14 72.39 0)
      (effects (font (size 1.27 1.27) (thickness 0.15)) (justify left bottom) hide)
    )
    (property "Datasheet" " " (at 358.14 69.85 0)
      (effects (font (size 1.27 1.27) (thickness 0.15)) (justify left bottom) hide)
    )
    (property "Manufacturer" "TDK" (at 358.14 64.77 0)
      (effects (font (size 1.27 1.27) (thickness 0.15)) (justify left bottom) hide)
    )
    (property "MPN" "C1005X6S1A105K050BC" (at 358.14 67.31 0)
      (effects (font (size 1.27 1.27) (thickness 0.15)) (justify left bottom) hide)
    )
    (property "Val" "1u" (at 378.46 83.82 0)
      (effects (font (size 1.27 1.27) (thickness 0.15)))
    )
    (property "License" "Apache-2.0" (at 358.14 62.23 0)
      (effects (font (size 1.27 1.27) (thickness 0.15)) (justify left bottom) hide)
    )
    (property "Author" "Antmicro" (at 358.14 59.69 0)
      (effects (font (size 1.27 1.27) (thickness 0.15)) (justify left bottom) hide)
    )
    (property "Voltage" "" (at 358.14 57.15 0)
      (effects (font (size 1.27 1.27)) (justify left bottom) hide)
    )
    (property "Dielectric" "" (at 358.14 54.61 0)
      (effects (font (size 1.27 1.27)) (justify left bottom) hide)
    )
    (pin "1")
    (pin "2")
    (instances
      (project "sdi-mipi-bridge"
        (path ""
          (reference "C62") (unit 1)
        )
      )
    )
  )

  (symbol (lib_id "sdi-mipi-bridge:C_47n_0402") (at 378.46 88.9 180) (unit 1)
    (in_bom yes) (on_board yes) (dnp no)
    (property "Reference" "C63" (at 373.38 87.63 0)
      (effects (font (size 1.27 1.27)))
    )
    (property "Value" "C_47n_0402" (at 358.14 78.74 0)
      (effects (font (size 1.27 1.27) (thickness 0.15)) (justify left bottom) hide)
    )
    (property "Footprint" "sdi-mipi-bridge-footprints:C_0402_1005Metric" (at 358.14 76.2 0)
      (effects (font (size 1.27 1.27) (thickness 0.15)) (justify left bottom) hide)
    )
    (property "Datasheet" " " (at 358.14 73.66 0)
      (effects (font (size 1.27 1.27) (thickness 0.15)) (justify left bottom) hide)
    )
    (property "Manufacturer" "Multicomp" (at 358.14 68.58 0)
      (effects (font (size 1.27 1.27) (thickness 0.15)) (justify left bottom) hide)
    )
    (property "MPN" "MC0402X473K160CT" (at 358.14 71.12 0)
      (effects (font (size 1.27 1.27) (thickness 0.15)) (justify left bottom) hide)
    )
    (property "Val" "47n" (at 378.46 87.63 0)
      (effects (font (size 1.27 1.27) (thickness 0.15)))
    )
    (property "License" "Apache-2.0" (at 358.14 66.04 0)
      (effects (font (size 1.27 1.27) (thickness 0.15)) (justify left bottom) hide)
    )
    (property "Author" "Antmicro" (at 358.14 63.5 0)
      (effects (font (size 1.27 1.27) (thickness 0.15)) (justify left bottom) hide)
    )
    (property "Voltage" "" (at 358.14 60.96 0)
      (effects (font (size 1.27 1.27)) (justify left bottom) hide)
    )
    (property "Dielectric" "" (at 358.14 58.42 0)
      (effects (font (size 1.27 1.27)) (justify left bottom) hide)
    )
    (pin "1")
    (pin "2")
    (instances
      (project "sdi-mipi-bridge"
        (path ""
          (reference "C63") (unit 1)
        )
      )
    )
  )

  (symbol (lib_id "sdi-mipi-bridge:R_0R_0402") (at 381 72.39 270) (unit 1)
    (in_bom yes) (on_board yes) (dnp no)
    (property "Reference" "R34" (at 383.54 73.6599 90)
      (effects (font (size 1.27 1.27)) (justify left))
    )
    (property "Value" "R_0R_0402" (at 368.3 92.71 0)
      (effects (font (size 1.27 1.27) (thickness 0.15)) (justify left bottom) hide)
    )
    (property "Footprint" "sdi-mipi-bridge-footprints:R_0402_1005Metric" (at 365.76 92.71 0)
      (effects (font (size 1.27 1.27) (thickness 0.15)) (justify left bottom) hide)
    )
    (property "Datasheet" "https://industrial.panasonic.com/cdbs/www-data/pdf/RDA0000/AOA0000C301.pdf" (at 363.22 92.71 0)
      (effects (font (size 1.27 1.27) (thickness 0.15)) (justify left bottom) hide)
    )
    (property "Manufacturer" "Panasonic" (at 358.14 92.71 0)
      (effects (font (size 1.27 1.27) (thickness 0.15)) (justify left bottom) hide)
    )
    (property "MPN" "ERJ2GE0R00X" (at 360.68 92.71 0)
      (effects (font (size 1.27 1.27) (thickness 0.15)) (justify left bottom) hide)
    )
    (property "Val" "0R" (at 383.54 76.1999 90)
      (effects (font (size 1.27 1.27) (thickness 0.15)) (justify left))
    )
    (property "License" "Apache-2.0" (at 355.6 92.71 0)
      (effects (font (size 1.27 1.27) (thickness 0.15)) (justify left bottom) hide)
    )
    (property "Author" "Antmicro" (at 353.06 92.71 0)
      (effects (font (size 1.27 1.27) (thickness 0.15)) (justify left bottom) hide)
    )
    (property "Tolerance" "~" (at 370.84 92.71 0)
      (effects (font (size 1.27 1.27)) (justify left bottom) hide)
    )
    (property "Current" "1A" (at 350.52 92.71 0)
      (effects (font (size 1.27 1.27) (thickness 0.15)) (justify left bottom) hide)
    )
    (property "DNP" "DNP" (at 381 74.93 0)
      (effects (font (size 1.27 1.27)))
    )
    (pin "1")
    (pin "2")
    (instances
      (project "sdi-mipi-bridge"
        (path ""
          (reference "R34") (unit 1)
        )
      )
    )
  )

  (symbol (lib_id "sdi-mipi-bridge:R_0R_0402") (at 373.38 80.01 0) (unit 1)
    (in_bom yes) (on_board yes) (dnp no)
    (property "Reference" "R32" (at 372.11 78.74 0)
      (effects (font (size 1.27 1.27)))
    )
    (property "Value" "R_0R_0402" (at 393.7 92.71 0)
      (effects (font (size 1.27 1.27) (thickness 0.15)) (justify left bottom) hide)
    )
    (property "Footprint" "sdi-mipi-bridge-footprints:R_0402_1005Metric" (at 393.7 95.25 0)
      (effects (font (size 1.27 1.27) (thickness 0.15)) (justify left bottom) hide)
    )
    (property "Datasheet" "https://industrial.panasonic.com/cdbs/www-data/pdf/RDA0000/AOA0000C301.pdf" (at 393.7 97.79 0)
      (effects (font (size 1.27 1.27) (thickness 0.15)) (justify left bottom) hide)
    )
    (property "Manufacturer" "Panasonic" (at 393.7 102.87 0)
      (effects (font (size 1.27 1.27) (thickness 0.15)) (justify left bottom) hide)
    )
    (property "MPN" "ERJ2GE0R00X" (at 393.7 100.33 0)
      (effects (font (size 1.27 1.27) (thickness 0.15)) (justify left bottom) hide)
    )
    (property "Val" "0R" (at 379.73 78.74 0)
      (effects (font (size 1.27 1.27) (thickness 0.15)))
    )
    (property "License" "Apache-2.0" (at 393.7 105.41 0)
      (effects (font (size 1.27 1.27) (thickness 0.15)) (justify left bottom) hide)
    )
    (property "Author" "Antmicro" (at 393.7 107.95 0)
      (effects (font (size 1.27 1.27) (thickness 0.15)) (justify left bottom) hide)
    )
    (property "Tolerance" "~" (at 393.7 90.17 0)
      (effects (font (size 1.27 1.27)) (justify left bottom) hide)
    )
    (property "Current" "1A" (at 393.7 110.49 0)
      (effects (font (size 1.27 1.27) (thickness 0.15)) (justify left bottom) hide)
    )
    (property "DNP" "DNP" (at 375.92 80.01 0)
      (effects (font (size 1.27 1.27)))
    )
    (pin "1")
    (pin "2")
    (instances
      (project "sdi-mipi-bridge"
        (path ""
          (reference "R32") (unit 1)
        )
      )
    )
  )

  (symbol (lib_id "sdi-mipi-bridge:+3.3VA") (at 381 71.12 0) (unit 1)
    (in_bom yes) (on_board yes) (dnp no)
    (property "Reference" "#PWR059" (at 381 74.93 0)
      (effects (font (size 1.27 1.27)) hide)
    )
    (property "Value" "+3.3VA" (at 381.381 66.7258 0)
      (effects (font (size 1.27 1.27)))
    )
    (property "Footprint" "" (at 381 71.12 0)
      (effects (font (size 1.27 1.27)) hide)
    )
    (property "Datasheet" "" (at 381 71.12 0)
      (effects (font (size 1.27 1.27)) hide)
    )
    (pin "1")
    (instances
      (project "sdi-mipi-bridge"
        (path ""
          (reference "#PWR059") (unit 1)
        )
      )
    )
  )

  (symbol (lib_id "sdi-mipi-bridge:GNDA") (at 370.84 90.17 0) (unit 1)
    (in_bom yes) (on_board yes) (dnp no)
    (property "Reference" "#PWR057" (at 370.84 96.52 0)
      (effects (font (size 1.27 1.27)) hide)
    )
    (property "Value" "GNDA" (at 370.967 94.5642 0)
      (effects (font (size 1.27 1.27)))
    )
    (property "Footprint" "" (at 370.84 90.17 0)
      (effects (font (size 1.27 1.27)) hide)
    )
    (property "Datasheet" "" (at 370.84 90.17 0)
      (effects (font (size 1.27 1.27)) hide)
    )
    (pin "1")
    (instances
      (project "sdi-mipi-bridge"
        (path ""
          (reference "#PWR057") (unit 1)
        )
      )
    )
  )

  (symbol (lib_id "sdi-mipi-bridge:MAX8902B") (at 52.07 228.6 0) (unit 1)
    (in_bom yes) (on_board yes) (dnp no) (fields_autoplaced)
    (property "Reference" "U1" (at 59.69 222.25 0)
      (effects (font (size 1.27 1.27)))
    )
    (property "Value" "MAX8902B" (at 57.15 243.84 0)
      (effects (font (size 1.27 1.27) (thickness 0.15)) (justify left bottom) hide)
    )
    (property "Footprint" "sdi-mipi-bridge-footprints:TDFN-8-1EP_2x2mm_P0.5mm" (at 80.01 241.3 0)
      (effects (font (size 1.27 1.27) (thickness 0.15)) (justify left bottom) hide)
    )
    (property "Datasheet" "https://www.analog.com/media/en/technical-documentation/data-sheets/MAX8902-MAX8902B.pdf" (at 80.01 243.84 0)
      (effects (font (size 1.27 1.27) (thickness 0.15)) (justify left bottom) hide)
    )
    (property "MPN" "MAX8902B" (at 59.69 224.79 0)
      (effects (font (size 1.27 1.27) (thickness 0.15)))
    )
    (property "Manufacturer" "Maxim Integrated Products" (at 80.01 246.38 0)
      (effects (font (size 1.27 1.27) (thickness 0.15)) (justify left bottom) hide)
    )
    (property "Author" "Antmicro" (at 80.01 248.92 0)
      (effects (font (size 1.27 1.27) (thickness 0.15)) (justify left bottom) hide)
    )
    (property "License" "Apache-2.0" (at 80.01 251.46 0)
      (effects (font (size 1.27 1.27) (thickness 0.15)) (justify left bottom) hide)
    )
    (pin "1")
    (pin "2")
    (pin "3")
    (pin "4")
    (pin "5")
    (pin "6")
    (pin "7")
    (pin "8")
    (pin "9")
    (instances
      (project "sdi-mipi-bridge"
        (path ""
          (reference "U1") (unit 1)
        )
      )
    )
  )

  (symbol (lib_id "sdi-mipi-bridge:C_10n_0402") (at 69.85 233.68 90) (unit 1)
    (in_bom yes) (on_board yes) (dnp no) (fields_autoplaced)
    (property "Reference" "C10" (at 72.39 229.8635 90)
      (effects (font (size 1.27 1.27)) (justify right))
    )
    (property "Value" "C_10n_0402" (at 73.66 233.68 0)
      (effects (font (size 1.27 1.27) (thickness 0.15)) (justify left bottom) hide)
    )
    (property "Footprint" "sdi-mipi-bridge-footprints:C_0402_1005Metric" (at 64.77 228.6 0)
      (effects (font (size 1.27 1.27) (thickness 0.15)) (justify left bottom) hide)
    )
    (property "Datasheet" "https://search.murata.co.jp/Ceramy/image/img/A01X/G101/ENG/GRM155R71H103KA88-01.pdf" (at 69.85 233.68 0)
      (effects (font (size 1.27 1.27) (thickness 0.15)) (justify left bottom) hide)
    )
    (property "Manufacturer" "Murata" (at 59.69 228.6 0)
      (effects (font (size 1.27 1.27) (thickness 0.15)) (justify left bottom) hide)
    )
    (property "MPN" "GRM155R71H103KA88D" (at 62.23 228.6 0)
      (effects (font (size 1.27 1.27) (thickness 0.15)) (justify left bottom) hide)
    )
    (property "Val" "10n" (at 72.39 232.4035 90)
      (effects (font (size 1.27 1.27) (thickness 0.15)) (justify right))
    )
    (property "License" "Apache-2.0" (at 92.71 213.36 0)
      (effects (font (size 1.27 1.27) (thickness 0.15)) (justify left bottom) hide)
    )
    (property "Author" "Antmicro" (at 95.25 213.36 0)
      (effects (font (size 1.27 1.27) (thickness 0.15)) (justify left bottom) hide)
    )
    (property "Voltage" "50V" (at 97.79 213.36 0)
      (effects (font (size 1.27 1.27)) (justify left bottom) hide)
    )
    (property "Dielectric" "X7R" (at 100.33 213.36 0)
      (effects (font (size 1.27 1.27)) (justify left bottom) hide)
    )
    (pin "1")
    (pin "2")
    (instances
      (project "sdi-mipi-bridge"
        (path ""
          (reference "C10") (unit 1)
        )
      )
    )
  )

  (symbol (lib_id "sdi-mipi-bridge:C_10u_0603") (at 87.63 241.3 90) (unit 1)
    (in_bom yes) (on_board yes) (dnp no) (fields_autoplaced)
    (property "Reference" "C15" (at 90.17 237.4835 90)
      (effects (font (size 1.27 1.27)) (justify right))
    )
    (property "Value" "C_10u_0603" (at 91.44 241.3 0)
      (effects (font (size 1.27 1.27) (thickness 0.15)) (justify left bottom) hide)
    )
    (property "Footprint" "sdi-mipi-bridge-footprints:C_0603_1608Metric" (at 82.55 236.22 0)
      (effects (font (size 1.27 1.27) (thickness 0.15)) (justify left bottom) hide)
    )
    (property "Datasheet" " " (at 87.63 241.3 0)
      (effects (font (size 1.27 1.27) (thickness 0.15)) (justify left bottom) hide)
    )
    (property "Manufacturer" "Murata" (at 77.47 236.22 0)
      (effects (font (size 1.27 1.27) (thickness 0.15)) (justify left bottom) hide)
    )
    (property "MPN" "GRM188R61A106KE69D" (at 80.01 236.22 0)
      (effects (font (size 1.27 1.27) (thickness 0.15)) (justify left bottom) hide)
    )
    (property "Val" "10u" (at 90.17 240.0235 90)
      (effects (font (size 1.27 1.27) (thickness 0.15)) (justify right))
    )
    (property "License" "Apache-2.0" (at 110.49 220.98 0)
      (effects (font (size 1.27 1.27) (thickness 0.15)) (justify left bottom) hide)
    )
    (property "Author" "Antmicro" (at 113.03 220.98 0)
      (effects (font (size 1.27 1.27) (thickness 0.15)) (justify left bottom) hide)
    )
    (property "Voltage" "" (at 115.57 220.98 0)
      (effects (font (size 1.27 1.27)) (justify left bottom) hide)
    )
    (pin "1")
    (pin "2")
    (instances
      (project "sdi-mipi-bridge"
        (path ""
          (reference "C15") (unit 1)
        )
      )
    )
  )

  (symbol (lib_id "sdi-mipi-bridge:C_10u_0603") (at 36.83 234.95 90) (unit 1)
    (in_bom yes) (on_board yes) (dnp no) (fields_autoplaced)
    (property "Reference" "C1" (at 39.37 231.1335 90)
      (effects (font (size 1.27 1.27)) (justify right))
    )
    (property "Value" "C_10u_0603" (at 40.64 234.95 0)
      (effects (font (size 1.27 1.27) (thickness 0.15)) (justify left bottom) hide)
    )
    (property "Footprint" "sdi-mipi-bridge-footprints:C_0603_1608Metric" (at 31.75 229.87 0)
      (effects (font (size 1.27 1.27) (thickness 0.15)) (justify left bottom) hide)
    )
    (property "Datasheet" " " (at 36.83 234.95 0)
      (effects (font (size 1.27 1.27) (thickness 0.15)) (justify left bottom) hide)
    )
    (property "Manufacturer" "Murata" (at 26.67 229.87 0)
      (effects (font (size 1.27 1.27) (thickness 0.15)) (justify left bottom) hide)
    )
    (property "MPN" "GRM188R61A106KE69D" (at 29.21 229.87 0)
      (effects (font (size 1.27 1.27) (thickness 0.15)) (justify left bottom) hide)
    )
    (property "Val" "10u" (at 39.37 233.6735 90)
      (effects (font (size 1.27 1.27) (thickness 0.15)) (justify right))
    )
    (property "License" "Apache-2.0" (at 59.69 214.63 0)
      (effects (font (size 1.27 1.27) (thickness 0.15)) (justify left bottom) hide)
    )
    (property "Author" "Antmicro" (at 62.23 214.63 0)
      (effects (font (size 1.27 1.27) (thickness 0.15)) (justify left bottom) hide)
    )
    (property "Voltage" "" (at 64.77 214.63 0)
      (effects (font (size 1.27 1.27)) (justify left bottom) hide)
    )
    (pin "1")
    (pin "2")
    (instances
      (project "sdi-mipi-bridge"
        (path ""
          (reference "C1") (unit 1)
        )
      )
    )
  )

  (symbol (lib_id "sdi-mipi-bridge:R_120k_0402") (at 78.74 240.03 270) (unit 1)
    (in_bom yes) (on_board yes) (dnp no) (fields_autoplaced)
    (property "Reference" "R6" (at 81.28 241.2999 90)
      (effects (font (size 1.27 1.27)) (justify left))
    )
    (property "Value" "R_120k_0402" (at 74.93 240.03 0)
      (effects (font (size 1.27 1.27) (thickness 0.15)) (justify left bottom) hide)
    )
    (property "Footprint" "sdi-mipi-bridge-footprints:R_0402_1005Metric" (at 83.82 245.11 0)
      (effects (font (size 1.27 1.27) (thickness 0.15)) (justify left bottom) hide)
    )
    (property "Datasheet" "https://www.bourns.com/docs/product-datasheets/cr.pdf" (at 78.74 240.03 0)
      (effects (font (size 1.27 1.27) (thickness 0.15)) (justify left bottom) hide)
    )
    (property "Manufacturer" "Bourns" (at 88.9 245.11 0)
      (effects (font (size 1.27 1.27) (thickness 0.15)) (justify left bottom) hide)
    )
    (property "MPN" "CR0402-FX-1203GLF" (at 86.36 245.11 0)
      (effects (font (size 1.27 1.27) (thickness 0.15)) (justify left bottom) hide)
    )
    (property "Val" "120k" (at 81.28 243.8399 90)
      (effects (font (size 1.27 1.27) (thickness 0.15)) (justify left))
    )
    (property "License" "Apache-2.0" (at 53.34 260.35 0)
      (effects (font (size 1.27 1.27) (thickness 0.15)) (justify left bottom) hide)
    )
    (property "Author" "Antmicro" (at 50.8 260.35 0)
      (effects (font (size 1.27 1.27) (thickness 0.15)) (justify left bottom) hide)
    )
    (property "Tolerance" "1%" (at 68.58 260.35 0)
      (effects (font (size 1.27 1.27)) (justify left bottom) hide)
    )
    (pin "1")
    (pin "2")
    (instances
      (project "sdi-mipi-bridge"
        (path ""
          (reference "R6") (unit 1)
        )
      )
    )
  )

  (symbol (lib_id "sdi-mipi-bridge:R_120k_0402") (at 78.74 229.87 270) (unit 1)
    (in_bom yes) (on_board yes) (dnp no) (fields_autoplaced)
    (property "Reference" "R5" (at 81.28 231.1399 90)
      (effects (font (size 1.27 1.27)) (justify left))
    )
    (property "Value" "R_120k_0402" (at 74.93 229.87 0)
      (effects (font (size 1.27 1.27) (thickness 0.15)) (justify left bottom) hide)
    )
    (property "Footprint" "sdi-mipi-bridge-footprints:R_0402_1005Metric" (at 83.82 234.95 0)
      (effects (font (size 1.27 1.27) (thickness 0.15)) (justify left bottom) hide)
    )
    (property "Datasheet" "https://www.bourns.com/docs/product-datasheets/cr.pdf" (at 78.74 229.87 0)
      (effects (font (size 1.27 1.27) (thickness 0.15)) (justify left bottom) hide)
    )
    (property "Manufacturer" "Bourns" (at 88.9 234.95 0)
      (effects (font (size 1.27 1.27) (thickness 0.15)) (justify left bottom) hide)
    )
    (property "MPN" "CR0402-FX-1203GLF" (at 86.36 234.95 0)
      (effects (font (size 1.27 1.27) (thickness 0.15)) (justify left bottom) hide)
    )
    (property "Val" "120k" (at 81.28 233.6799 90)
      (effects (font (size 1.27 1.27) (thickness 0.15)) (justify left))
    )
    (property "License" "Apache-2.0" (at 53.34 250.19 0)
      (effects (font (size 1.27 1.27) (thickness 0.15)) (justify left bottom) hide)
    )
    (property "Author" "Antmicro" (at 50.8 250.19 0)
      (effects (font (size 1.27 1.27) (thickness 0.15)) (justify left bottom) hide)
    )
    (property "Tolerance" "1%" (at 68.58 250.19 0)
      (effects (font (size 1.27 1.27)) (justify left bottom) hide)
    )
    (pin "1")
    (pin "2")
    (instances
      (project "sdi-mipi-bridge"
        (path ""
          (reference "R5") (unit 1)
        )
      )
    )
  )

  (symbol (lib_id "sdi-mipi-bridge:R_0R_0402") (at 157.48 349.25 0) (unit 1)
    (in_bom yes) (on_board yes) (dnp no)
    (property "Reference" "R25" (at 160.02 346.71 0)
      (effects (font (size 1.27 1.27)))
    )
    (property "Value" "R_0R_0402" (at 177.8 361.95 0)
      (effects (font (size 1.27 1.27) (thickness 0.15)) (justify left bottom) hide)
    )
    (property "Footprint" "sdi-mipi-bridge-footprints:R_0402_1005Metric" (at 177.8 364.49 0)
      (effects (font (size 1.27 1.27) (thickness 0.15)) (justify left bottom) hide)
    )
    (property "Datasheet" "https://industrial.panasonic.com/cdbs/www-data/pdf/RDA0000/AOA0000C301.pdf" (at 177.8 367.03 0)
      (effects (font (size 1.27 1.27) (thickness 0.15)) (justify left bottom) hide)
    )
    (property "Manufacturer" "Panasonic" (at 177.8 372.11 0)
      (effects (font (size 1.27 1.27) (thickness 0.15)) (justify left bottom) hide)
    )
    (property "MPN" "ERJ2GE0R00X" (at 177.8 369.57 0)
      (effects (font (size 1.27 1.27) (thickness 0.15)) (justify left bottom) hide)
    )
    (property "Val" "0R" (at 160.02 351.79 0)
      (effects (font (size 1.27 1.27) (thickness 0.15)))
    )
    (property "License" "Apache-2.0" (at 177.8 374.65 0)
      (effects (font (size 1.27 1.27) (thickness 0.15)) (justify left bottom) hide)
    )
    (property "Author" "Antmicro" (at 177.8 377.19 0)
      (effects (font (size 1.27 1.27) (thickness 0.15)) (justify left bottom) hide)
    )
    (property "Tolerance" "~" (at 177.8 359.41 0)
      (effects (font (size 1.27 1.27)) (justify left bottom) hide)
    )
    (property "Current" "1A" (at 177.8 379.73 0)
      (effects (font (size 1.27 1.27) (thickness 0.15)) (justify left bottom) hide)
    )
    (pin "1")
    (pin "2")
    (instances
      (project "sdi-mipi-bridge"
        (path ""
          (reference "R25") (unit 1)
        )
      )
    )
  )

  (symbol (lib_id "sdi-mipi-bridge:R_22R_0402") (at 52.07 64.77 0) (unit 1)
    (in_bom yes) (on_board yes) (dnp no)
    (property "Reference" "R3" (at 50.8 63.5 0)
      (effects (font (size 1.27 1.27)))
    )
    (property "Value" "R_22R_0402" (at 72.39 77.47 0)
      (effects (font (size 1.27 1.27) (thickness 0.15)) (justify left bottom) hide)
    )
    (property "Footprint" "sdi-mipi-bridge-footprints:R_0402_1005Metric" (at 72.39 80.01 0)
      (effects (font (size 1.27 1.27) (thickness 0.15)) (justify left bottom) hide)
    )
    (property "Datasheet" "https://www.bourns.com/docs/product-datasheets/cr.pdf" (at 72.39 82.55 0)
      (effects (font (size 1.27 1.27) (thickness 0.15)) (justify left bottom) hide)
    )
    (property "Manufacturer" "Bourns" (at 72.39 87.63 0)
      (effects (font (size 1.27 1.27) (thickness 0.15)) (justify left bottom) hide)
    )
    (property "MPN" "CR0402-FX-22R0GLF" (at 72.39 85.09 0)
      (effects (font (size 1.27 1.27) (thickness 0.15)) (justify left bottom) hide)
    )
    (property "Val" "22R" (at 59.69 63.5 0)
      (effects (font (size 1.27 1.27) (thickness 0.15)))
    )
    (property "License" "Apache-2.0" (at 72.39 90.17 0)
      (effects (font (size 1.27 1.27) (thickness 0.15)) (justify left bottom) hide)
    )
    (property "Author" "Antmicro" (at 72.39 92.71 0)
      (effects (font (size 1.27 1.27) (thickness 0.15)) (justify left bottom) hide)
    )
    (property "Tolerance" "1%" (at 72.39 74.93 0)
      (effects (font (size 1.27 1.27)) (justify left bottom) hide)
    )
    (pin "1")
    (pin "2")
    (instances
      (project "sdi-mipi-bridge"
        (path ""
          (reference "R3") (unit 1)
        )
      )
    )
  )

  (symbol (lib_id "sdi-mipi-bridge:R_22R_0402") (at 52.07 67.31 0) (unit 1)
    (in_bom yes) (on_board yes) (dnp no)
    (property "Reference" "R2" (at 50.8 66.04 0)
      (effects (font (size 1.27 1.27)))
    )
    (property "Value" "R_22R_0402" (at 72.39 80.01 0)
      (effects (font (size 1.27 1.27) (thickness 0.15)) (justify left bottom) hide)
    )
    (property "Footprint" "sdi-mipi-bridge-footprints:R_0402_1005Metric" (at 72.39 82.55 0)
      (effects (font (size 1.27 1.27) (thickness 0.15)) (justify left bottom) hide)
    )
    (property "Datasheet" "https://www.bourns.com/docs/product-datasheets/cr.pdf" (at 72.39 85.09 0)
      (effects (font (size 1.27 1.27) (thickness 0.15)) (justify left bottom) hide)
    )
    (property "Manufacturer" "Bourns" (at 72.39 90.17 0)
      (effects (font (size 1.27 1.27) (thickness 0.15)) (justify left bottom) hide)
    )
    (property "MPN" "CR0402-FX-22R0GLF" (at 72.39 87.63 0)
      (effects (font (size 1.27 1.27) (thickness 0.15)) (justify left bottom) hide)
    )
    (property "Val" "22R" (at 59.69 66.04 0)
      (effects (font (size 1.27 1.27) (thickness 0.15)))
    )
    (property "License" "Apache-2.0" (at 72.39 92.71 0)
      (effects (font (size 1.27 1.27) (thickness 0.15)) (justify left bottom) hide)
    )
    (property "Author" "Antmicro" (at 72.39 95.25 0)
      (effects (font (size 1.27 1.27) (thickness 0.15)) (justify left bottom) hide)
    )
    (property "Tolerance" "1%" (at 72.39 77.47 0)
      (effects (font (size 1.27 1.27)) (justify left bottom) hide)
    )
    (pin "1")
    (pin "2")
    (instances
      (project "sdi-mipi-bridge"
        (path ""
          (reference "R2") (unit 1)
        )
      )
    )
  )

  (symbol (lib_id "sdi-mipi-bridge:R_22R_0402") (at 52.07 69.85 0) (unit 1)
    (in_bom yes) (on_board yes) (dnp no)
    (property "Reference" "R1" (at 50.8 68.58 0)
      (effects (font (size 1.27 1.27)))
    )
    (property "Value" "R_22R_0402" (at 72.39 82.55 0)
      (effects (font (size 1.27 1.27) (thickness 0.15)) (justify left bottom) hide)
    )
    (property "Footprint" "sdi-mipi-bridge-footprints:R_0402_1005Metric" (at 72.39 85.09 0)
      (effects (font (size 1.27 1.27) (thickness 0.15)) (justify left bottom) hide)
    )
    (property "Datasheet" "https://www.bourns.com/docs/product-datasheets/cr.pdf" (at 72.39 87.63 0)
      (effects (font (size 1.27 1.27) (thickness 0.15)) (justify left bottom) hide)
    )
    (property "Manufacturer" "Bourns" (at 72.39 92.71 0)
      (effects (font (size 1.27 1.27) (thickness 0.15)) (justify left bottom) hide)
    )
    (property "MPN" "CR0402-FX-22R0GLF" (at 72.39 90.17 0)
      (effects (font (size 1.27 1.27) (thickness 0.15)) (justify left bottom) hide)
    )
    (property "Val" "22R" (at 59.69 68.58 0)
      (effects (font (size 1.27 1.27) (thickness 0.15)))
    )
    (property "License" "Apache-2.0" (at 72.39 95.25 0)
      (effects (font (size 1.27 1.27) (thickness 0.15)) (justify left bottom) hide)
    )
    (property "Author" "Antmicro" (at 72.39 97.79 0)
      (effects (font (size 1.27 1.27) (thickness 0.15)) (justify left bottom) hide)
    )
    (property "Tolerance" "1%" (at 72.39 80.01 0)
      (effects (font (size 1.27 1.27)) (justify left bottom) hide)
    )
    (pin "1")
    (pin "2")
    (instances
      (project "sdi-mipi-bridge"
        (path ""
          (reference "R1") (unit 1)
        )
      )
    )
  )

  (symbol (lib_id "sdi-mipi-bridge:GNDREF") (at 87.63 247.65 0) (unit 1)
    (in_bom yes) (on_board yes) (dnp no)
    (property "Reference" "#PWR014" (at 87.63 254 0)
      (effects (font (size 1.27 1.27)) hide)
    )
    (property "Value" "GNDREF" (at 87.757 252.0442 0)
      (effects (font (size 1.27 1.27)))
    )
    (property "Footprint" "" (at 87.63 247.65 0)
      (effects (font (size 1.27 1.27)) hide)
    )
    (property "Datasheet" "" (at 87.63 247.65 0)
      (effects (font (size 1.27 1.27)) hide)
    )
    (pin "1")
    (instances
      (project "sdi-mipi-bridge"
        (path ""
          (reference "#PWR014") (unit 1)
        )
      )
    )
  )

  (symbol (lib_id "sdi-mipi-bridge:SC18IS602BIPW") (at 520.7 41.91 0) (unit 1)
    (in_bom yes) (on_board yes) (dnp no) (fields_autoplaced)
    (property "Reference" "U5" (at 534.67 34.29 0)
      (effects (font (size 1.27 1.27)))
    )
    (property "Value" "SC18IS602BIPW" (at 534.67 36.83 0)
      (effects (font (size 1.27 1.27) (thickness 0.15)))
    )
    (property "Footprint" "sdi-mipi-bridge-footprints:TSSOP-16_4.4x5mm_P0.65mm" (at 574.04 49.53 0)
      (effects (font (size 1.27 1.27) (thickness 0.15)) (justify left bottom) hide)
    )
    (property "Datasheet" "https://www.nxp.com/docs/en/data-sheet/SC18IS602B.pdf" (at 574.04 52.07 0)
      (effects (font (size 1.27 1.27) (thickness 0.15)) (justify left bottom) hide)
    )
    (property "MPN" "SC18IS602BIPW" (at 574.04 57.15 0)
      (effects (font (size 1.27 1.27) (thickness 0.15)) (justify left bottom) hide)
    )
    (property "Manufacturer" "NXP" (at 574.04 54.61 0)
      (effects (font (size 1.27 1.27) (thickness 0.15)) (justify left bottom) hide)
    )
    (property "Author" "Antmicro" (at 574.04 59.69 0)
      (effects (font (size 1.27 1.27) (thickness 0.15)) (justify left bottom) hide)
    )
    (property "License" "Apache-2.0" (at 574.04 62.23 0)
      (effects (font (size 1.27 1.27) (thickness 0.15)) (justify left bottom) hide)
    )
    (pin "1")
    (pin "10")
    (pin "11")
    (pin "12")
    (pin "13")
    (pin "14")
    (pin "15")
    (pin "16")
    (pin "2")
    (pin "3")
    (pin "4")
    (pin "5")
    (pin "6")
    (pin "7")
    (pin "8")
    (pin "9")
    (instances
      (project "sdi-mipi-bridge"
        (path ""
          (reference "U5") (unit 1)
        )
      )
    )
  )

  (symbol (lib_id "sdi-mipi-bridge:GNDREF") (at 69.85 247.65 0) (unit 1)
    (in_bom yes) (on_board yes) (dnp no)
    (property "Reference" "#PWR08" (at 69.85 254 0)
      (effects (font (size 1.27 1.27)) hide)
    )
    (property "Value" "GNDREF" (at 69.977 252.0442 0)
      (effects (font (size 1.27 1.27)))
    )
    (property "Footprint" "" (at 69.85 247.65 0)
      (effects (font (size 1.27 1.27)) hide)
    )
    (property "Datasheet" "" (at 69.85 247.65 0)
      (effects (font (size 1.27 1.27)) hide)
    )
    (pin "1")
    (instances
      (project "sdi-mipi-bridge"
        (path ""
          (reference "#PWR08") (unit 1)
        )
      )
    )
  )

  (symbol (lib_id "sdi-mipi-bridge:+1V2") (at 87.63 226.06 0) (unit 1)
    (in_bom yes) (on_board yes) (dnp no)
    (property "Reference" "#PWR016" (at 87.63 229.87 0)
      (effects (font (size 1.27 1.27)) hide)
    )
    (property "Value" "+1V2" (at 88.011 221.6658 0)
      (effects (font (size 1.27 1.27)))
    )
    (property "Footprint" "" (at 87.63 226.06 0)
      (effects (font (size 1.27 1.27)) hide)
    )
    (property "Datasheet" "" (at 87.63 226.06 0)
      (effects (font (size 1.27 1.27)) hide)
    )
    (pin "1")
    (instances
      (project "sdi-mipi-bridge"
        (path ""
          (reference "#PWR016") (unit 1)
        )
      )
    )
  )

  (symbol (lib_id "sdi-mipi-bridge:GNDREF") (at 78.74 247.65 0) (unit 1)
    (in_bom yes) (on_board yes) (dnp no)
    (property "Reference" "#PWR013" (at 78.74 254 0)
      (effects (font (size 1.27 1.27)) hide)
    )
    (property "Value" "GNDREF" (at 78.867 252.0442 0)
      (effects (font (size 1.27 1.27)))
    )
    (property "Footprint" "" (at 78.74 247.65 0)
      (effects (font (size 1.27 1.27)) hide)
    )
    (property "Datasheet" "" (at 78.74 247.65 0)
      (effects (font (size 1.27 1.27)) hide)
    )
    (pin "1")
    (instances
      (project "sdi-mipi-bridge"
        (path ""
          (reference "#PWR013") (unit 1)
        )
      )
    )
  )

  (symbol (lib_id "sdi-mipi-bridge:R_100R_0402") (at 346.71 222.25 0) (mirror y) (unit 1)
    (in_bom yes) (on_board yes) (dnp no)
    (property "Reference" "R88" (at 344.17 219.71 0)
      (effects (font (size 1.27 1.27)))
    )
    (property "Value" "R_100R_0402" (at 346.71 226.06 0)
      (effects (font (size 1.27 1.27) (thickness 0.15)) (justify left bottom) hide)
    )
    (property "Footprint" "sdi-mipi-bridge-footprints:R_0402_1005Metric" (at 341.63 217.17 0)
      (effects (font (size 1.27 1.27) (thickness 0.15)) (justify left bottom) hide)
    )
    (property "Datasheet" "https://www.bourns.com/docs/product-datasheets/cr.pdf" (at 346.71 222.25 0)
      (effects (font (size 1.27 1.27) (thickness 0.15)) (justify left bottom) hide)
    )
    (property "Manufacturer" "Bourns" (at 341.63 212.09 0)
      (effects (font (size 1.27 1.27) (thickness 0.15)) (justify left bottom) hide)
    )
    (property "MPN" "CR0402-FX-1000GLF" (at 341.63 214.63 0)
      (effects (font (size 1.27 1.27) (thickness 0.15)) (justify left bottom) hide)
    )
    (property "Val" "100R" (at 344.17 224.79 0)
      (effects (font (size 1.27 1.27) (thickness 0.15)))
    )
    (property "License" "Apache-2.0" (at 326.39 247.65 0)
      (effects (font (size 1.27 1.27) (thickness 0.15)) (justify left bottom) hide)
    )
    (property "Author" "Antmicro" (at 326.39 250.19 0)
      (effects (font (size 1.27 1.27) (thickness 0.15)) (justify left bottom) hide)
    )
    (property "Tolerance" "1%" (at 326.39 232.41 0)
      (effects (font (size 1.27 1.27)) (justify left bottom) hide)
    )
    (pin "1")
    (pin "2")
    (instances
      (project "sdi-mipi-bridge"
        (path ""
          (reference "R88") (unit 1)
        )
      )
    )
  )

  (symbol (lib_id "sdi-mipi-bridge:LED_G_0603_LG_L29K-G2J1-24-Z") (at 354.33 222.25 0) (mirror x) (unit 1)
    (in_bom yes) (on_board yes) (dnp no)
    (property "Reference" "D2" (at 358.14 219.71 0)
      (effects (font (size 1.27 1.27)))
    )
    (property "Value" "LED_G_0603_LG_L29K-G2J1-24-Z" (at 361.95 228.6 0)
      (effects (font (size 1.27 1.27) (thickness 0.15)) (justify left bottom) hide)
    )
    (property "Footprint" "sdi-mipi-bridge-footprints:LED_0603_1608Metric_G" (at 359.41 227.33 0)
      (effects (font (size 1.27 1.27) (thickness 0.15)) (justify left bottom) hide)
    )
    (property "Datasheet" "https://dammedia.osram.info/media/resource/hires/osram-dam-2493945/LG%20L29K.pdf" (at 359.41 229.87 0)
      (effects (font (size 1.27 1.27) (thickness 0.15)) (justify left bottom) hide)
    )
    (property "MPN" "LG L29K-G2J1-24-Z" (at 358.14 226.06 0)
      (effects (font (size 1.27 1.27) (thickness 0.15)))
    )
    (property "Manufacturer" "Osram" (at 359.41 250.19 0)
      (effects (font (size 1.27 1.27) (thickness 0.15)) (justify left bottom) hide)
    )
    (property "Author" "Antmicro" (at 377.19 201.93 0)
      (effects (font (size 1.27 1.27) (thickness 0.15)) (justify left bottom) hide)
    )
    (property "License" "Apache-2.0" (at 377.19 199.39 0)
      (effects (font (size 1.27 1.27) (thickness 0.15)) (justify left bottom) hide)
    )
    (pin "1")
    (pin "2")
    (instances
      (project "sdi-mipi-bridge"
        (path ""
          (reference "D2") (unit 1)
        )
      )
    )
  )

  (symbol (lib_id "sdi-mipi-bridge:TP_1mm_SMD") (at 52.07 241.3 180) (unit 1)
    (in_bom yes) (on_board yes) (dnp no)
    (property "Reference" "TP6" (at 45.72 241.3 0)
      (effects (font (size 1.27 1.27)))
    )
    (property "Value" "TP_1mm_SMD" (at 52.07 238.76 0)
      (effects (font (size 1.27 1.27) (thickness 0.15)) (justify left bottom) hide)
    )
    (property "Footprint" "sdi-mipi-bridge-footprints:Testpoint_smd_1mm" (at 46.99 246.38 0)
      (effects (font (size 1.27 1.27) (thickness 0.15)) (justify left bottom) hide)
    )
    (property "Datasheet" "" (at 46.99 248.92 0)
      (effects (font (size 1.27 1.27) (thickness 0.15)) (justify left bottom) hide)
    )
    (property "MPN" "" (at 52.07 241.3 0)
      (effects (font (size 1.27 1.27)) hide)
    )
    (property "Manufacturer" "" (at 52.07 241.3 0)
      (effects (font (size 1.27 1.27)) hide)
    )
    (property "Author" "Antmicro" (at 36.83 226.06 0)
      (effects (font (size 1.27 1.27) (thickness 0.15)) (justify left bottom) hide)
    )
    (property "License" "Apache-2.0" (at 36.83 223.52 0)
      (effects (font (size 1.27 1.27) (thickness 0.15)) (justify left bottom) hide)
    )
    (pin "1")
    (instances
      (project "sdi-mipi-bridge"
        (path ""
          (reference "TP6") (unit 1)
        )
      )
    )
  )

  (symbol (lib_id "sdi-mipi-bridge:R_75R_0603") (at 259.08 142.24 270) (unit 1)
    (in_bom yes) (on_board yes) (dnp no)
    (property "Reference" "R28" (at 260.35 143.51 90)
      (effects (font (size 1.27 1.27)) (justify left))
    )
    (property "Value" "R_75R_0603" (at 246.38 162.56 0)
      (effects (font (size 1.27 1.27) (thickness 0.15)) (justify left bottom) hide)
    )
    (property "Footprint" "sdi-mipi-bridge-footprints:R_0603_1608Metric" (at 243.84 162.56 0)
      (effects (font (size 1.27 1.27) (thickness 0.15)) (justify left bottom) hide)
    )
    (property "Datasheet" "https://www.bourns.com/docs/product-datasheets/cr.pdf" (at 241.3 162.56 0)
      (effects (font (size 1.27 1.27) (thickness 0.15)) (justify left bottom) hide)
    )
    (property "Manufacturer" "Bourns" (at 236.22 162.56 0)
      (effects (font (size 1.27 1.27) (thickness 0.15)) (justify left bottom) hide)
    )
    (property "MPN" "CR0603-FX-75R0ELF" (at 238.76 162.56 0)
      (effects (font (size 1.27 1.27) (thickness 0.15)) (justify left bottom) hide)
    )
    (property "Val" "75R" (at 260.35 146.05 90)
      (effects (font (size 1.27 1.27) (thickness 0.15)) (justify left))
    )
    (property "License" "Apache-2.0" (at 233.68 162.56 0)
      (effects (font (size 1.27 1.27) (thickness 0.15)) (justify left bottom) hide)
    )
    (property "Author" "Antmicro" (at 231.14 162.56 0)
      (effects (font (size 1.27 1.27) (thickness 0.15)) (justify left bottom) hide)
    )
    (property "Tolerance" "1%" (at 248.92 162.56 0)
      (effects (font (size 1.27 1.27)) (justify left bottom) hide)
    )
    (pin "1")
    (pin "2")
    (instances
      (project "sdi-mipi-bridge"
        (path ""
          (reference "R28") (unit 1)
        )
      )
    )
  )

  (symbol (lib_id "sdi-mipi-bridge:R_75R_0603") (at 256.54 140.97 180) (unit 1)
    (in_bom yes) (on_board yes) (dnp no)
    (property "Reference" "R27" (at 254 138.43 0)
      (effects (font (size 1.27 1.27)))
    )
    (property "Value" "R_75R_0603" (at 236.22 128.27 0)
      (effects (font (size 1.27 1.27) (thickness 0.15)) (justify left bottom) hide)
    )
    (property "Footprint" "sdi-mipi-bridge-footprints:R_0603_1608Metric" (at 236.22 125.73 0)
      (effects (font (size 1.27 1.27) (thickness 0.15)) (justify left bottom) hide)
    )
    (property "Datasheet" "https://www.bourns.com/docs/product-datasheets/cr.pdf" (at 236.22 123.19 0)
      (effects (font (size 1.27 1.27) (thickness 0.15)) (justify left bottom) hide)
    )
    (property "Manufacturer" "Bourns" (at 236.22 118.11 0)
      (effects (font (size 1.27 1.27) (thickness 0.15)) (justify left bottom) hide)
    )
    (property "MPN" "CR0603-FX-75R0ELF" (at 236.22 120.65 0)
      (effects (font (size 1.27 1.27) (thickness 0.15)) (justify left bottom) hide)
    )
    (property "Val" "75R" (at 254 143.51 0)
      (effects (font (size 1.27 1.27) (thickness 0.15)))
    )
    (property "License" "Apache-2.0" (at 236.22 115.57 0)
      (effects (font (size 1.27 1.27) (thickness 0.15)) (justify left bottom) hide)
    )
    (property "Author" "Antmicro" (at 236.22 113.03 0)
      (effects (font (size 1.27 1.27) (thickness 0.15)) (justify left bottom) hide)
    )
    (property "Tolerance" "1%" (at 236.22 130.81 0)
      (effects (font (size 1.27 1.27)) (justify left bottom) hide)
    )
    (pin "1")
    (pin "2")
    (instances
      (project "sdi-mipi-bridge"
        (path ""
          (reference "R27") (unit 1)
        )
      )
    )
  )

  (symbol (lib_id "sdi-mipi-bridge:GNDREF") (at 36.83 234.95 0) (unit 1)
    (in_bom yes) (on_board yes) (dnp no)
    (property "Reference" "#PWR02" (at 36.83 241.3 0)
      (effects (font (size 1.27 1.27)) hide)
    )
    (property "Value" "GNDREF" (at 36.957 239.3442 0)
      (effects (font (size 1.27 1.27)))
    )
    (property "Footprint" "" (at 36.83 234.95 0)
      (effects (font (size 1.27 1.27)) hide)
    )
    (property "Datasheet" "" (at 36.83 234.95 0)
      (effects (font (size 1.27 1.27)) hide)
    )
    (pin "1")
    (instances
      (project "sdi-mipi-bridge"
        (path ""
          (reference "#PWR02") (unit 1)
        )
      )
    )
  )

  (symbol (lib_id "sdi-mipi-bridge:C_6n2_0603") (at 251.46 133.35 0) (unit 1)
    (in_bom yes) (on_board yes) (dnp no)
    (property "Reference" "C43" (at 254 130.81 0)
      (effects (font (size 1.27 1.27)))
    )
    (property "Value" "C_6n2_0603" (at 271.78 143.51 0)
      (effects (font (size 1.27 1.27) (thickness 0.15)) (justify left bottom) hide)
    )
    (property "Footprint" "sdi-mipi-bridge-footprints:C_0603_1608Metric" (at 271.78 146.05 0)
      (effects (font (size 1.27 1.27) (thickness 0.15)) (justify left bottom) hide)
    )
    (property "Datasheet" " " (at 271.78 148.59 0)
      (effects (font (size 1.27 1.27) (thickness 0.15)) (justify left bottom) hide)
    )
    (property "Manufacturer" "KEMET" (at 271.78 153.67 0)
      (effects (font (size 1.27 1.27) (thickness 0.15)) (justify left bottom) hide)
    )
    (property "MPN" "C0603C622J5GACAUTO" (at 271.78 151.13 0)
      (effects (font (size 1.27 1.27) (thickness 0.15)) (justify left bottom) hide)
    )
    (property "Val" "6n2" (at 254 135.89 0)
      (effects (font (size 1.27 1.27) (thickness 0.15)))
    )
    (property "License" "Apache-2.0" (at 271.78 156.21 0)
      (effects (font (size 1.27 1.27) (thickness 0.15)) (justify left bottom) hide)
    )
    (property "Author" "Antmicro" (at 271.78 158.75 0)
      (effects (font (size 1.27 1.27) (thickness 0.15)) (justify left bottom) hide)
    )
    (property "Voltage" "" (at 271.78 161.29 0)
      (effects (font (size 1.27 1.27)) (justify left bottom) hide)
    )
    (property "Dielectric" "" (at 271.78 163.83 0)
      (effects (font (size 1.27 1.27)) (justify left bottom) hide)
    )
    (pin "1")
    (pin "2")
    (instances
      (project "sdi-mipi-bridge"
        (path ""
          (reference "C43") (unit 1)
        )
      )
    )
  )

  (symbol (lib_id "sdi-mipi-bridge:R_37R4_0402") (at 259.08 157.48 270) (unit 1)
    (in_bom yes) (on_board yes) (dnp no)
    (property "Reference" "R29" (at 260.35 158.75 90)
      (effects (font (size 1.27 1.27)) (justify left))
    )
    (property "Value" "R_37R4_0402" (at 246.38 177.8 0)
      (effects (font (size 1.27 1.27) (thickness 0.15)) (justify left bottom) hide)
    )
    (property "Footprint" "sdi-mipi-bridge-footprints:R_0402_1005Metric" (at 243.84 177.8 0)
      (effects (font (size 1.27 1.27) (thickness 0.15)) (justify left bottom) hide)
    )
    (property "Datasheet" "https://www.bourns.com/docs/product-datasheets/cr.pdf" (at 241.3 177.8 0)
      (effects (font (size 1.27 1.27) (thickness 0.15)) (justify left bottom) hide)
    )
    (property "Manufacturer" "Bourns" (at 236.22 177.8 0)
      (effects (font (size 1.27 1.27) (thickness 0.15)) (justify left bottom) hide)
    )
    (property "MPN" "CR0402-FX-37R4GLF" (at 238.76 177.8 0)
      (effects (font (size 1.27 1.27) (thickness 0.15)) (justify left bottom) hide)
    )
    (property "Val" "37R4" (at 260.35 161.29 90)
      (effects (font (size 1.27 1.27) (thickness 0.15)) (justify left))
    )
    (property "License" "Apache-2.0" (at 233.68 177.8 0)
      (effects (font (size 1.27 1.27) (thickness 0.15)) (justify left bottom) hide)
    )
    (property "Author" "Antmicro" (at 231.14 177.8 0)
      (effects (font (size 1.27 1.27) (thickness 0.15)) (justify left bottom) hide)
    )
    (property "Tolerance" "1%" (at 248.92 177.8 0)
      (effects (font (size 1.27 1.27)) (justify left bottom) hide)
    )
    (pin "1")
    (pin "2")
    (instances
      (project "sdi-mipi-bridge"
        (path ""
          (reference "R29") (unit 1)
        )
      )
    )
  )

  (symbol (lib_id "sdi-mipi-bridge:C_5n6_0402") (at 170.18 167.64 0) (unit 1)
    (in_bom yes) (on_board yes) (dnp no)
    (property "Reference" "C27" (at 172.72 162.56 0)
      (effects (font (size 1.27 1.27)))
    )
    (property "Value" "C_5n6_0402" (at 190.5 177.8 0)
      (effects (font (size 1.27 1.27) (thickness 0.15)) (justify left bottom) hide)
    )
    (property "Footprint" "sdi-mipi-bridge-footprints:C_0402_1005Metric" (at 190.5 180.34 0)
      (effects (font (size 1.27 1.27) (thickness 0.15)) (justify left bottom) hide)
    )
    (property "Datasheet" " " (at 190.5 182.88 0)
      (effects (font (size 1.27 1.27) (thickness 0.15)) (justify left bottom) hide)
    )
    (property "Manufacturer" "Multicomp" (at 190.5 187.96 0)
      (effects (font (size 1.27 1.27) (thickness 0.15)) (justify left bottom) hide)
    )
    (property "MPN" "MC0402B562K160CT" (at 190.5 185.42 0)
      (effects (font (size 1.27 1.27) (thickness 0.15)) (justify left bottom) hide)
    )
    (property "Val" "5n6" (at 172.72 165.1 0)
      (effects (font (size 1.27 1.27) (thickness 0.15)))
    )
    (property "License" "Apache-2.0" (at 190.5 190.5 0)
      (effects (font (size 1.27 1.27) (thickness 0.15)) (justify left bottom) hide)
    )
    (property "Author" "Antmicro" (at 190.5 193.04 0)
      (effects (font (size 1.27 1.27) (thickness 0.15)) (justify left bottom) hide)
    )
    (property "Voltage" "" (at 190.5 195.58 0)
      (effects (font (size 1.27 1.27)) (justify left bottom) hide)
    )
    (property "Dielectric" "" (at 190.5 198.12 0)
      (effects (font (size 1.27 1.27)) (justify left bottom) hide)
    )
    (pin "1")
    (pin "2")
    (instances
      (project "sdi-mipi-bridge"
        (path ""
          (reference "C27") (unit 1)
        )
      )
    )
  )

  (symbol (lib_id "sdi-mipi-bridge:R_750R_0402") (at 144.78 166.37 180) (unit 1)
    (in_bom yes) (on_board yes) (dnp no)
    (property "Reference" "R4" (at 142.24 163.83 0)
      (effects (font (size 1.27 1.27)))
    )
    (property "Value" "R_750R_0402" (at 124.46 153.67 0)
      (effects (font (size 1.27 1.27) (thickness 0.15)) (justify left bottom) hide)
    )
    (property "Footprint" "sdi-mipi-bridge-footprints:R_0402_1005Metric" (at 124.46 151.13 0)
      (effects (font (size 1.27 1.27) (thickness 0.15)) (justify left bottom) hide)
    )
    (property "Datasheet" "https://www.bourns.com/docs/product-datasheets/cr.pdf" (at 124.46 148.59 0)
      (effects (font (size 1.27 1.27) (thickness 0.15)) (justify left bottom) hide)
    )
    (property "Manufacturer" "Bourns" (at 124.46 143.51 0)
      (effects (font (size 1.27 1.27) (thickness 0.15)) (justify left bottom) hide)
    )
    (property "MPN" "CR0402-FX-7500GLF" (at 124.46 146.05 0)
      (effects (font (size 1.27 1.27) (thickness 0.15)) (justify left bottom) hide)
    )
    (property "Val" "750R" (at 142.24 168.91 0)
      (effects (font (size 1.27 1.27) (thickness 0.15)))
    )
    (property "License" "Apache-2.0" (at 124.46 140.97 0)
      (effects (font (size 1.27 1.27) (thickness 0.15)) (justify left bottom) hide)
    )
    (property "Author" "Antmicro" (at 124.46 138.43 0)
      (effects (font (size 1.27 1.27) (thickness 0.15)) (justify left bottom) hide)
    )
    (property "Tolerance" "1%" (at 124.46 156.21 0)
      (effects (font (size 1.27 1.27)) (justify left bottom) hide)
    )
    (pin "1")
    (pin "2")
    (instances
      (project "sdi-mipi-bridge"
        (path ""
          (reference "R4") (unit 1)
        )
      )
    )
  )

  (symbol (lib_id "sdi-mipi-bridge:Conn_BNC_031-70526-21") (at 245.11 140.97 0) (mirror y) (unit 1)
    (in_bom yes) (on_board yes) (dnp no) (fields_autoplaced)
    (property "Reference" "J2" (at 240.4109 137.16 0)
      (effects (font (size 1.27 1.27)))
    )
    (property "Value" "Conn_BNC_031-70526-21" (at 224.79 148.59 0)
      (effects (font (size 1.27 1.27) (thickness 0.15)) (justify left bottom) hide)
    )
    (property "Footprint" "sdi-mipi-bridge-footprints:Conn_BNC_031-70526-21" (at 224.79 151.13 0)
      (effects (font (size 1.27 1.27) (thickness 0.15)) (justify left bottom) hide)
    )
    (property "Datasheet" "https://www.farnell.com/cad/2305565.pdf?_ga=2.190633003.1014497200.1574067480-156563690.1566371002&_gac=1.57062104.1572875319.Cj0KCQiAtf_tBRDtARIsAIbAKe0A1M5y_jdFCiNLNrHM5L2GjmDvn_4qnRvhHAD9jBdL9AmoMNThLCoaAjhJEALw_wcB" (at 224.79 153.67 0)
      (effects (font (size 1.27 1.27) (thickness 0.15)) (justify left bottom) hide)
    )
    (property "MPN" "031-70526-21" (at 224.79 156.21 0)
      (effects (font (size 1.27 1.27) (thickness 0.15)) (justify left bottom) hide)
    )
    (property "Manufacturer" "Amphenol" (at 224.79 158.75 0)
      (effects (font (size 1.27 1.27) (thickness 0.15)) (justify left bottom) hide)
    )
    (property "Author" "Antmicro" (at 224.79 161.29 0)
      (effects (font (size 1.27 1.27) (thickness 0.15)) (justify left bottom) hide)
    )
    (property "License" "Apache-2.0" (at 224.79 163.83 0)
      (effects (font (size 1.27 1.27) (thickness 0.15)) (justify left bottom) hide)
    )
    (pin "1")
    (pin "2")
    (instances
      (project "sdi-mipi-bridge"
        (path ""
          (reference "J2") (unit 1)
        )
      )
    )
  )

  (symbol (lib_id "sdi-mipi-bridge:GNDA") (at 259.08 148.59 0) (unit 1)
    (in_bom yes) (on_board yes) (dnp no)
    (property "Reference" "#PWR048" (at 259.08 154.94 0)
      (effects (font (size 1.27 1.27)) hide)
    )
    (property "Value" "GNDA" (at 259.08 152.4 0)
      (effects (font (size 1.27 1.27)))
    )
    (property "Footprint" "" (at 259.08 148.59 0)
      (effects (font (size 1.27 1.27)) hide)
    )
    (property "Datasheet" "" (at 259.08 148.59 0)
      (effects (font (size 1.27 1.27)) hide)
    )
    (pin "1")
    (instances
      (project "sdi-mipi-bridge"
        (path ""
          (reference "#PWR048") (unit 1)
        )
      )
    )
  )

  (symbol (lib_id "sdi-mipi-bridge:GNDREF") (at 261.62 382.27 0) (unit 1)
    (in_bom yes) (on_board yes) (dnp no)
    (property "Reference" "#PWR0101" (at 261.62 388.62 0)
      (effects (font (size 1.27 1.27)) hide)
    )
    (property "Value" "GNDREF" (at 261.747 386.6642 0)
      (effects (font (size 1.27 1.27)))
    )
    (property "Footprint" "" (at 261.62 382.27 0)
      (effects (font (size 1.27 1.27)) hide)
    )
    (property "Datasheet" "" (at 261.62 382.27 0)
      (effects (font (size 1.27 1.27)) hide)
    )
    (pin "1")
    (instances
      (project "sdi-mipi-bridge"
        (path ""
          (reference "#PWR0101") (unit 1)
        )
      )
    )
  )

  (symbol (lib_id "sdi-mipi-bridge:R_0R_0402") (at 265.43 372.11 0) (unit 1)
    (in_bom yes) (on_board yes) (dnp no)
    (property "Reference" "R69" (at 264.16 370.84 0)
      (effects (font (size 1.27 1.27)))
    )
    (property "Value" "R_0R_0402" (at 265.43 375.92 0)
      (effects (font (size 1.524 1.524)) hide)
    )
    (property "Footprint" "sdi-mipi-bridge-footprints:R_0402_1005Metric" (at 270.51 367.03 0)
      (effects (font (size 1.524 1.524)) (justify left) hide)
    )
    (property "Datasheet" "https://industrial.panasonic.com/cdbs/www-data/pdf/RDA0000/AOA0000C301.pdf" (at 265.43 372.11 0)
      (effects (font (size 1.27 1.27)) hide)
    )
    (property "Manufacturer" "Panasonic" (at 270.51 361.95 0)
      (effects (font (size 1.524 1.524)) (justify left) hide)
    )
    (property "MPN" "ERJ2GE0R00X" (at 270.51 364.49 0)
      (effects (font (size 1.524 1.524)) (justify left) hide)
    )
    (property "Val" "0R" (at 271.78 370.84 0)
      (effects (font (size 1.27 1.27)))
    )
    (property "License" "Apache-2.0" (at 285.75 397.51 0)
      (effects (font (size 1.27 1.27) (thickness 0.15)) (justify left bottom) hide)
    )
    (property "Author" "Antmicro" (at 285.75 400.05 0)
      (effects (font (size 1.27 1.27) (thickness 0.15)) (justify left bottom) hide)
    )
    (property "Tolerance" "~" (at 285.75 382.27 0)
      (effects (font (size 1.27 1.27)) (justify left bottom) hide)
    )
    (property "Current" "1A" (at 285.75 402.59 0)
      (effects (font (size 1.27 1.27) (thickness 0.15)) (justify left bottom) hide)
    )
    (pin "1")
    (pin "2")
    (instances
      (project "sdi-mipi-bridge"
        (path ""
          (reference "R69") (unit 1)
        )
      )
    )
  )

  (symbol (lib_id "sdi-mipi-bridge:R_0R_0402") (at 265.43 378.46 0) (unit 1)
    (in_bom yes) (on_board yes) (dnp no)
    (property "Reference" "R70" (at 264.16 377.19 0)
      (effects (font (size 1.27 1.27)))
    )
    (property "Value" "R_0R_0402" (at 265.43 382.27 0)
      (effects (font (size 1.524 1.524)) hide)
    )
    (property "Footprint" "sdi-mipi-bridge-footprints:R_0402_1005Metric" (at 270.51 373.38 0)
      (effects (font (size 1.524 1.524)) (justify left) hide)
    )
    (property "Datasheet" "https://industrial.panasonic.com/cdbs/www-data/pdf/RDA0000/AOA0000C301.pdf" (at 265.43 378.46 0)
      (effects (font (size 1.27 1.27)) hide)
    )
    (property "Manufacturer" "Panasonic" (at 270.51 368.3 0)
      (effects (font (size 1.524 1.524)) (justify left) hide)
    )
    (property "MPN" "ERJ2GE0R00X" (at 270.51 370.84 0)
      (effects (font (size 1.524 1.524)) (justify left) hide)
    )
    (property "Val" "0R" (at 271.78 377.19 0)
      (effects (font (size 1.27 1.27)))
    )
    (property "License" "Apache-2.0" (at 285.75 403.86 0)
      (effects (font (size 1.27 1.27) (thickness 0.15)) (justify left bottom) hide)
    )
    (property "Author" "Antmicro" (at 285.75 406.4 0)
      (effects (font (size 1.27 1.27) (thickness 0.15)) (justify left bottom) hide)
    )
    (property "Tolerance" "~" (at 285.75 388.62 0)
      (effects (font (size 1.27 1.27)) (justify left bottom) hide)
    )
    (property "Current" "1A" (at 285.75 408.94 0)
      (effects (font (size 1.27 1.27) (thickness 0.15)) (justify left bottom) hide)
    )
    (pin "1")
    (pin "2")
    (instances
      (project "sdi-mipi-bridge"
        (path ""
          (reference "R70") (unit 1)
        )
      )
    )
  )

  (symbol (lib_id "sdi-mipi-bridge:CrossLink_LIF-MD6000-6JMG80I") (at 459.74 241.3 0) (unit 1)
    (in_bom yes) (on_board yes) (dnp no) (fields_autoplaced)
    (property "Reference" "U4" (at 491.49 233.68 0)
      (effects (font (size 1.27 1.27)))
    )
    (property "Value" "CrossLink_LIF-MD6000-6JMG80I" (at 541.02 354.33 0)
      (effects (font (size 1.27 1.27) (thickness 0.15)) (justify left bottom) hide)
    )
    (property "Footprint" "sdi-mipi-bridge-footprints:BGA-80_7x7mm_Layout10x10_P0.65mm" (at 538.48 255.27 0)
      (effects (font (size 1.27 1.27) (thickness 0.15)) (justify left bottom) hide)
    )
    (property "Datasheet" "https://www.latticesemi.com/view_document?document_id=51662" (at 538.48 257.81 0)
      (effects (font (size 1.27 1.27) (thickness 0.15)) (justify left bottom) hide)
    )
    (property "MPN" "LIF-MD6000-6JMG80I" (at 491.49 236.22 0)
      (effects (font (size 1.27 1.27) (thickness 0.15)))
    )
    (property "Manufacturer" "Lattice Semiconductor" (at 538.48 260.35 0)
      (effects (font (size 1.27 1.27) (thickness 0.15)) (justify left bottom) hide)
    )
    (property "Author" "Antmicro" (at 538.48 262.89 0)
      (effects (font (size 1.27 1.27) (thickness 0.15)) (justify left bottom) hide)
    )
    (property "License" "Apache-2.0" (at 538.48 265.43 0)
      (effects (font (size 1.27 1.27) (thickness 0.15)) (justify left bottom) hide)
    )
    (pin "A1")
    (pin "A10")
    (pin "A2")
    (pin "A3")
    (pin "A4")
    (pin "A5")
    (pin "A6")
    (pin "A7")
    (pin "A8")
    (pin "A9")
    (pin "B1")
    (pin "B10")
    (pin "B2")
    (pin "B3")
    (pin "B4")
    (pin "B5")
    (pin "B6")
    (pin "B7")
    (pin "B8")
    (pin "B9")
    (pin "C1")
    (pin "C10")
    (pin "C2")
    (pin "C9")
    (pin "D1")
    (pin "D10")
    (pin "D2")
    (pin "D4")
    (pin "D5")
    (pin "D6")
    (pin "D7")
    (pin "D9")
    (pin "E1")
    (pin "E10")
    (pin "E2")
    (pin "E4")
    (pin "E5")
    (pin "E6")
    (pin "E7")
    (pin "E9")
    (pin "F1")
    (pin "F10")
    (pin "F2")
    (pin "F4")
    (pin "F5")
    (pin "F6")
    (pin "F7")
    (pin "F9")
    (pin "G1")
    (pin "G10")
    (pin "G2")
    (pin "G4")
    (pin "G5")
    (pin "G6")
    (pin "G7")
    (pin "G9")
    (pin "H1")
    (pin "H10")
    (pin "H2")
    (pin "H9")
    (pin "J1")
    (pin "J10")
    (pin "J2")
    (pin "J3")
    (pin "J4")
    (pin "J5")
    (pin "J6")
    (pin "J7")
    (pin "J8")
    (pin "J9")
    (pin "K1")
    (pin "K10")
    (pin "K2")
    (pin "K3")
    (pin "K4")
    (pin "K5")
    (pin "K6")
    (pin "K7")
    (pin "K8")
    (pin "K9")
    (instances
      (project "sdi-mipi-bridge"
        (path ""
          (reference "U4") (unit 1)
        )
      )
    )
  )

  (symbol (lib_id "sdi-mipi-bridge:GNDA") (at 240.03 146.05 0) (unit 1)
    (in_bom yes) (on_board yes) (dnp no)
    (property "Reference" "#PWR0111" (at 240.03 152.4 0)
      (effects (font (size 1.27 1.27)) hide)
    )
    (property "Value" "GNDA" (at 240.157 150.4442 0)
      (effects (font (size 1.27 1.27)))
    )
    (property "Footprint" "" (at 240.03 146.05 0)
      (effects (font (size 1.27 1.27)) hide)
    )
    (property "Datasheet" "" (at 240.03 146.05 0)
      (effects (font (size 1.27 1.27)) hide)
    )
    (pin "1")
    (instances
      (project "sdi-mipi-bridge"
        (path ""
          (reference "#PWR0111") (unit 1)
        )
      )
    )
  )

  (symbol (lib_id "sdi-mipi-bridge:GNDA") (at 194.31 165.1 0) (unit 1)
    (in_bom yes) (on_board yes) (dnp no)
    (property "Reference" "#PWR0112" (at 194.31 171.45 0)
      (effects (font (size 1.27 1.27)) hide)
    )
    (property "Value" "GNDA" (at 194.437 169.4942 0)
      (effects (font (size 1.27 1.27)))
    )
    (property "Footprint" "" (at 194.31 165.1 0)
      (effects (font (size 1.27 1.27)) hide)
    )
    (property "Datasheet" "" (at 194.31 165.1 0)
      (effects (font (size 1.27 1.27)) hide)
    )
    (pin "1")
    (instances
      (project "sdi-mipi-bridge"
        (path ""
          (reference "#PWR0112") (unit 1)
        )
      )
    )
  )

  (symbol (lib_id "sdi-mipi-bridge:R_0R_0402") (at 547.37 322.58 0) (mirror y) (unit 1)
    (in_bom yes) (on_board yes) (dnp no)
    (property "Reference" "R90" (at 541.02 321.31 0)
      (effects (font (size 1.27 1.27)))
    )
    (property "Value" "R_0R_0402" (at 547.37 326.39 0)
      (effects (font (size 1.27 1.27) (thickness 0.15)) (justify left bottom) hide)
    )
    (property "Footprint" "sdi-mipi-bridge-footprints:R_0402_1005Metric" (at 542.29 317.5 0)
      (effects (font (size 1.27 1.27) (thickness 0.15)) (justify left bottom) hide)
    )
    (property "Datasheet" "https://industrial.panasonic.com/cdbs/www-data/pdf/RDA0000/AOA0000C301.pdf" (at 547.37 322.58 0)
      (effects (font (size 1.27 1.27) (thickness 0.15)) (justify left bottom) hide)
    )
    (property "Manufacturer" "Panasonic" (at 542.29 312.42 0)
      (effects (font (size 1.27 1.27) (thickness 0.15)) (justify left bottom) hide)
    )
    (property "MPN" "ERJ2GE0R00X" (at 542.29 314.96 0)
      (effects (font (size 1.27 1.27) (thickness 0.15)) (justify left bottom) hide)
    )
    (property "Val" "0R" (at 549.91 322.58 0)
      (effects (font (size 1.27 1.27) (thickness 0.15)) (justify left bottom))
    )
    (property "License" "Apache-2.0" (at 527.05 347.98 0)
      (effects (font (size 1.27 1.27) (thickness 0.15)) (justify left bottom) hide)
    )
    (property "Author" "Antmicro" (at 527.05 350.52 0)
      (effects (font (size 1.27 1.27) (thickness 0.15)) (justify left bottom) hide)
    )
    (property "Tolerance" "~" (at 527.05 332.74 0)
      (effects (font (size 1.27 1.27)) (justify left bottom) hide)
    )
    (property "Current" "1A" (at 527.05 353.06 0)
      (effects (font (size 1.27 1.27) (thickness 0.15)) (justify left bottom) hide)
    )
    (pin "1")
    (pin "2")
    (instances
      (project "sdi-mipi-bridge"
        (path ""
          (reference "R90") (unit 1)
        )
      )
    )
  )

  (symbol (lib_id "sdi-mipi-bridge:R_0R_0402") (at 547.37 284.48 0) (mirror y) (unit 1)
    (in_bom yes) (on_board yes) (dnp no)
    (property "Reference" "R91" (at 541.02 283.21 0)
      (effects (font (size 1.27 1.27)))
    )
    (property "Value" "R_0R_0402" (at 547.37 288.29 0)
      (effects (font (size 1.27 1.27) (thickness 0.15)) (justify left bottom) hide)
    )
    (property "Footprint" "sdi-mipi-bridge-footprints:R_0402_1005Metric" (at 542.29 279.4 0)
      (effects (font (size 1.27 1.27) (thickness 0.15)) (justify left bottom) hide)
    )
    (property "Datasheet" "https://industrial.panasonic.com/cdbs/www-data/pdf/RDA0000/AOA0000C301.pdf" (at 547.37 284.48 0)
      (effects (font (size 1.27 1.27) (thickness 0.15)) (justify left bottom) hide)
    )
    (property "Manufacturer" "Panasonic" (at 542.29 274.32 0)
      (effects (font (size 1.27 1.27) (thickness 0.15)) (justify left bottom) hide)
    )
    (property "MPN" "ERJ2GE0R00X" (at 542.29 276.86 0)
      (effects (font (size 1.27 1.27) (thickness 0.15)) (justify left bottom) hide)
    )
    (property "Val" "0R" (at 548.64 283.21 0)
      (effects (font (size 1.27 1.27) (thickness 0.15)))
    )
    (property "License" "Apache-2.0" (at 527.05 309.88 0)
      (effects (font (size 1.27 1.27) (thickness 0.15)) (justify left bottom) hide)
    )
    (property "Author" "Antmicro" (at 527.05 312.42 0)
      (effects (font (size 1.27 1.27) (thickness 0.15)) (justify left bottom) hide)
    )
    (property "Tolerance" "~" (at 527.05 294.64 0)
      (effects (font (size 1.27 1.27)) (justify left bottom) hide)
    )
    (property "Current" "1A" (at 527.05 314.96 0)
      (effects (font (size 1.27 1.27) (thickness 0.15)) (justify left bottom) hide)
    )
    (pin "1")
    (pin "2")
    (instances
      (project "sdi-mipi-bridge"
        (path ""
          (reference "R91") (unit 1)
        )
      )
    )
  )

  (symbol (lib_id "sdi-mipi-bridge:GS2988") (at 111.76 143.51 0) (unit 1)
    (in_bom yes) (on_board yes) (dnp no) (fields_autoplaced)
    (property "Reference" "U3" (at 123.19 134.62 0)
      (effects (font (size 1.27 1.27)))
    )
    (property "Value" "GS2988" (at 123.19 138.43 0)
      (effects (font (size 1.27 1.27) (thickness 0.15)))
    )
    (property "Footprint" "sdi-mipi-bridge-footprints:QFN-16_1EP_4x4mm_P0.65mm" (at 167.64 153.67 0)
      (effects (font (size 1.27 1.27) (thickness 0.15)) (justify left bottom) hide)
    )
    (property "Datasheet" "https://semtech.my.salesforce.com/sfc/p/#E0000000JelG/a/44000000MDIY/URmNPYk6YrvngFjCh2n.ZRVsjLb90QOH1YLezdH9vhM" (at 167.64 156.21 0)
      (effects (font (size 1.27 1.27) (thickness 0.15)) (justify left bottom) hide)
    )
    (property "MPN" "GS2988-INE3" (at 167.64 161.29 0)
      (effects (font (size 1.27 1.27) (thickness 0.15)) (justify left bottom) hide)
    )
    (property "Manufacturer" "Semtech" (at 167.64 158.75 0)
      (effects (font (size 1.27 1.27) (thickness 0.15)) (justify left bottom) hide)
    )
    (property "Author" "Antmicro" (at 167.64 163.83 0)
      (effects (font (size 1.27 1.27) (thickness 0.15)) (justify left bottom) hide)
    )
    (property "License" "Apache-2.0" (at 167.64 166.37 0)
      (effects (font (size 1.27 1.27) (thickness 0.15)) (justify left bottom) hide)
    )
    (pin "1")
    (pin "10")
    (pin "11")
    (pin "12")
    (pin "13")
    (pin "14")
    (pin "15")
    (pin "16")
    (pin "17")
    (pin "2")
    (pin "3")
    (pin "4")
    (pin "5")
    (pin "6")
    (pin "7")
    (pin "8")
    (pin "9")
    (instances
      (project "sdi-mipi-bridge"
        (path ""
          (reference "U3") (unit 1)
        )
      )
    )
  )

  (symbol (lib_id "sdi-mipi-bridge:GNDREF") (at 441.96 229.87 0) (unit 1)
    (in_bom yes) (on_board yes) (dnp no)
    (property "Reference" "#PWR0107" (at 441.96 236.22 0)
      (effects (font (size 1.27 1.27)) hide)
    )
    (property "Value" "GNDREF" (at 442.087 234.2642 0)
      (effects (font (size 1.27 1.27)))
    )
    (property "Footprint" "" (at 441.96 229.87 0)
      (effects (font (size 1.27 1.27)) hide)
    )
    (property "Datasheet" "" (at 441.96 229.87 0)
      (effects (font (size 1.27 1.27)) hide)
    )
    (pin "1")
    (instances
      (project "sdi-mipi-bridge"
        (path ""
          (reference "#PWR0107") (unit 1)
        )
      )
    )
  )

  (symbol (lib_id "sdi-mipi-bridge:R_0R_0402") (at 450.85 229.87 270) (unit 1)
    (in_bom yes) (on_board yes) (dnp no)
    (property "Reference" "R89" (at 452.12 231.14 90)
      (effects (font (size 1.27 1.27)) (justify left))
    )
    (property "Value" "R_0R_0402" (at 447.04 229.87 0)
      (effects (font (size 1.27 1.27) (thickness 0.15)) (justify left bottom) hide)
    )
    (property "Footprint" "sdi-mipi-bridge-footprints:R_0402_1005Metric" (at 455.93 234.95 0)
      (effects (font (size 1.27 1.27) (thickness 0.15)) (justify left bottom) hide)
    )
    (property "Datasheet" "https://industrial.panasonic.com/cdbs/www-data/pdf/RDA0000/AOA0000C301.pdf" (at 450.85 229.87 0)
      (effects (font (size 1.27 1.27) (thickness 0.15)) (justify left bottom) hide)
    )
    (property "Manufacturer" "Panasonic" (at 461.01 234.95 0)
      (effects (font (size 1.27 1.27) (thickness 0.15)) (justify left bottom) hide)
    )
    (property "MPN" "ERJ2GE0R00X" (at 458.47 234.95 0)
      (effects (font (size 1.27 1.27) (thickness 0.15)) (justify left bottom) hide)
    )
    (property "Val" "0R" (at 452.12 233.68 90)
      (effects (font (size 1.27 1.27) (thickness 0.15)) (justify left))
    )
    (property "License" "Apache-2.0" (at 425.45 250.19 0)
      (effects (font (size 1.27 1.27) (thickness 0.15)) (justify left bottom) hide)
    )
    (property "Author" "Antmicro" (at 422.91 250.19 0)
      (effects (font (size 1.27 1.27) (thickness 0.15)) (justify left bottom) hide)
    )
    (property "Tolerance" "~" (at 440.69 250.19 0)
      (effects (font (size 1.27 1.27)) (justify left bottom) hide)
    )
    (property "Current" "1A" (at 420.37 250.19 0)
      (effects (font (size 1.27 1.27) (thickness 0.15)) (justify left bottom) hide)
    )
    (property "DNP" "DNP" (at 450.85 229.87 0)
      (effects (font (size 1.27 1.27)) hide)
    )
    (pin "1")
    (pin "2")
    (instances
      (project "sdi-mipi-bridge"
        (path ""
          (reference "R89") (unit 1)
        )
      )
    )
  )

  (symbol (lib_id "sdi-mipi-bridge:C_1u_0402") (at 165.1 355.6 90) (unit 1)
    (in_bom yes) (on_board yes) (dnp no) (fields_autoplaced)
    (property "Reference" "C35" (at 167.64 351.7835 90)
      (effects (font (size 1.27 1.27)) (justify right))
    )
    (property "Value" "C_1u_0402" (at 175.26 335.28 0)
      (effects (font (size 1.27 1.27) (thickness 0.15)) (justify left bottom) hide)
    )
    (property "Footprint" "sdi-mipi-bridge-footprints:C_0402_1005Metric" (at 177.8 335.28 0)
      (effects (font (size 1.27 1.27) (thickness 0.15)) (justify left bottom) hide)
    )
    (property "Datasheet" " " (at 180.34 335.28 0)
      (effects (font (size 1.27 1.27) (thickness 0.15)) (justify left bottom) hide)
    )
    (property "Manufacturer" "TDK" (at 185.42 335.28 0)
      (effects (font (size 1.27 1.27) (thickness 0.15)) (justify left bottom) hide)
    )
    (property "MPN" "C1005X6S1A105K050BC" (at 182.88 335.28 0)
      (effects (font (size 1.27 1.27) (thickness 0.15)) (justify left bottom) hide)
    )
    (property "Val" "1u" (at 167.64 354.3235 90)
      (effects (font (size 1.27 1.27) (thickness 0.15)) (justify right))
    )
    (property "License" "Apache-2.0" (at 187.96 335.28 0)
      (effects (font (size 1.27 1.27) (thickness 0.15)) (justify left bottom) hide)
    )
    (property "Author" "Antmicro" (at 190.5 335.28 0)
      (effects (font (size 1.27 1.27) (thickness 0.15)) (justify left bottom) hide)
    )
    (property "Voltage" "" (at 193.04 335.28 0)
      (effects (font (size 1.27 1.27)) (justify left bottom) hide)
    )
    (property "Dielectric" "" (at 195.58 335.28 0)
      (effects (font (size 1.27 1.27)) (justify left bottom) hide)
    )
    (pin "1")
    (pin "2")
    (instances
      (project "sdi-mipi-bridge"
        (path ""
          (reference "C35") (unit 1)
        )
      )
    )
  )

  (symbol (lib_id "sdi-mipi-bridge:GNDREF") (at 165.1 355.6 0) (unit 1)
    (in_bom yes) (on_board yes) (dnp no)
    (property "Reference" "#PWR033" (at 165.1 361.95 0)
      (effects (font (size 1.27 1.27)) hide)
    )
    (property "Value" "GNDREF" (at 165.1 359.41 0)
      (effects (font (size 1.27 1.27)))
    )
    (property "Footprint" "" (at 165.1 355.6 0)
      (effects (font (size 1.27 1.27)) hide)
    )
    (property "Datasheet" "" (at 165.1 355.6 0)
      (effects (font (size 1.27 1.27)) hide)
    )
    (pin "1")
    (instances
      (project "sdi-mipi-bridge"
        (path ""
          (reference "#PWR033") (unit 1)
        )
      )
    )
  )

  (symbol (lib_id "sdi-mipi-bridge:oshw_logo") (at 44.45 186.69 0) (unit 1)
    (in_bom yes) (on_board yes) (dnp no) (fields_autoplaced)
    (property "Reference" "N2" (at 50.8 184.3975 0)
      (effects (font (size 1.27 1.27)) (justify left))
    )
    (property "Value" "oshw_logo" (at 50.8 186.9375 0)
      (effects (font (size 1.27 1.27) (thickness 0.15)) (justify left))
    )
    (property "Footprint" "sdi-mipi-bridge-footprints:oshw-logo" (at 44.958 192.786 0)
      (effects (font (size 1.27 1.27) (thickness 0.15)) (justify left bottom) hide)
    )
    (property "Datasheet" "" (at 44.45 186.69 0)
      (effects (font (size 1.27 1.27) (thickness 0.15)) (justify left bottom) hide)
    )
    (property "Author" "Antmicro" (at 59.69 201.93 0)
      (effects (font (size 1.27 1.27) (thickness 0.15)) (justify left bottom) hide)
    )
    (property "License" "Apache-2.0" (at 59.69 204.47 0)
      (effects (font (size 1.27 1.27) (thickness 0.15)) (justify left bottom) hide)
    )
    (property "MPN" "" (at 44.45 186.69 0)
      (effects (font (size 1.27 1.27)) hide)
    )
    (property "Manufacturer" "" (at 59.69 207.01 0)
      (effects (font (size 1.27 1.27) (thickness 0.15)) (justify left bottom) hide)
    )
    (instances
      (project "sdi-mipi-bridge"
        (path ""
          (reference "N2") (unit 1)
        )
      )
    )
  )

  (symbol (lib_id "sdi-mipi-bridge:R_100R_0402") (at 346.71 203.2 0) (mirror y) (unit 1)
    (in_bom yes) (on_board yes) (dnp no)
    (property "Reference" "R33" (at 345.44 200.66 0)
      (effects (font (size 1.27 1.27)) (justify left))
    )
    (property "Value" "R_100R_0402" (at 346.71 207.01 0)
      (effects (font (size 1.27 1.27) (thickness 0.15)) (justify left bottom) hide)
    )
    (property "Footprint" "sdi-mipi-bridge-footprints:R_0402_1005Metric" (at 341.63 198.12 0)
      (effects (font (size 1.27 1.27) (thickness 0.15)) (justify left bottom) hide)
    )
    (property "Datasheet" "https://www.bourns.com/docs/product-datasheets/cr.pdf" (at 346.71 203.2 0)
      (effects (font (size 1.27 1.27) (thickness 0.15)) (justify left bottom) hide)
    )
    (property "Manufacturer" "Bourns" (at 341.63 193.04 0)
      (effects (font (size 1.27 1.27) (thickness 0.15)) (justify left bottom) hide)
    )
    (property "MPN" "CR0402-FX-1000GLF" (at 341.63 195.58 0)
      (effects (font (size 1.27 1.27) (thickness 0.15)) (justify left bottom) hide)
    )
    (property "Val" "100R" (at 346.71 207.01 0)
      (effects (font (size 1.27 1.27) (thickness 0.15)) (justify left bottom))
    )
    (property "License" "Apache-2.0" (at 326.39 228.6 0)
      (effects (font (size 1.27 1.27) (thickness 0.15)) (justify left bottom) hide)
    )
    (property "Author" "Antmicro" (at 326.39 231.14 0)
      (effects (font (size 1.27 1.27) (thickness 0.15)) (justify left bottom) hide)
    )
    (property "Tolerance" "1%" (at 326.39 213.36 0)
      (effects (font (size 1.27 1.27)) (justify left bottom) hide)
    )
    (pin "1")
    (pin "2")
    (instances
      (project "sdi-mipi-bridge"
        (path ""
          (reference "R33") (unit 1)
        )
      )
    )
  )

  (symbol (lib_id "sdi-mipi-bridge:LED_G_0603_LG_L29K-G2J1-24-Z") (at 354.33 203.2 0) (mirror x) (unit 1)
    (in_bom yes) (on_board yes) (dnp no)
    (property "Reference" "D1" (at 358.14 200.66 0)
      (effects (font (size 1.27 1.27)))
    )
    (property "Value" "LED_G_0603_LG_L29K-G2J1-24-Z" (at 361.95 209.55 0)
      (effects (font (size 1.27 1.27) (thickness 0.15)) (justify left bottom) hide)
    )
    (property "Footprint" "sdi-mipi-bridge-footprints:LED_0603_1608Metric_G" (at 359.41 208.28 0)
      (effects (font (size 1.27 1.27) (thickness 0.15)) (justify left bottom) hide)
    )
    (property "Datasheet" "https://dammedia.osram.info/media/resource/hires/osram-dam-2493945/LG%20L29K.pdf" (at 359.41 210.82 0)
      (effects (font (size 1.27 1.27) (thickness 0.15)) (justify left bottom) hide)
    )
    (property "MPN" "LG L29K-G2J1-24-Z" (at 358.14 207.01 0)
      (effects (font (size 1.27 1.27) (thickness 0.15)))
    )
    (property "Manufacturer" "Osram" (at 359.41 231.14 0)
      (effects (font (size 1.27 1.27) (thickness 0.15)) (justify left bottom) hide)
    )
    (property "Author" "Antmicro" (at 377.19 182.88 0)
      (effects (font (size 1.27 1.27) (thickness 0.15)) (justify left bottom) hide)
    )
    (property "License" "Apache-2.0" (at 377.19 180.34 0)
      (effects (font (size 1.27 1.27) (thickness 0.15)) (justify left bottom) hide)
    )
    (pin "1")
    (pin "2")
    (instances
      (project "sdi-mipi-bridge"
        (path ""
          (reference "D1") (unit 1)
        )
      )
    )
  )

  (symbol (lib_id "sdi-mipi-bridge:C_10n_0402") (at 175.26 311.15 90) (unit 1)
    (in_bom yes) (on_board yes) (dnp no) (fields_autoplaced)
    (property "Reference" "C34" (at 177.8 307.3335 90)
      (effects (font (size 1.27 1.27)) (justify right))
    )
    (property "Value" "C_10n_0402" (at 185.42 290.83 0)
      (effects (font (size 1.27 1.27) (thickness 0.15)) (justify left bottom) hide)
    )
    (property "Footprint" "sdi-mipi-bridge-footprints:C_0402_1005Metric" (at 187.96 290.83 0)
      (effects (font (size 1.27 1.27) (thickness 0.15)) (justify left bottom) hide)
    )
    (property "Datasheet" "https://search.murata.co.jp/Ceramy/image/img/A01X/G101/ENG/GRM155R71H103KA88-01.pdf" (at 190.5 290.83 0)
      (effects (font (size 1.27 1.27) (thickness 0.15)) (justify left bottom) hide)
    )
    (property "Manufacturer" "Murata" (at 195.58 290.83 0)
      (effects (font (size 1.27 1.27) (thickness 0.15)) (justify left bottom) hide)
    )
    (property "MPN" "GRM155R71H103KA88D" (at 193.04 290.83 0)
      (effects (font (size 1.27 1.27) (thickness 0.15)) (justify left bottom) hide)
    )
    (property "Val" "10n" (at 177.8 309.8735 90)
      (effects (font (size 1.27 1.27) (thickness 0.15)) (justify right))
    )
    (property "License" "Apache-2.0" (at 198.12 290.83 0)
      (effects (font (size 1.27 1.27) (thickness 0.15)) (justify left bottom) hide)
    )
    (property "Author" "Antmicro" (at 200.66 290.83 0)
      (effects (font (size 1.27 1.27) (thickness 0.15)) (justify left bottom) hide)
    )
    (property "Voltage" "50V" (at 203.2 290.83 0)
      (effects (font (size 1.27 1.27)) (justify left bottom) hide)
    )
    (property "Dielectric" "X7R" (at 205.74 290.83 0)
      (effects (font (size 1.27 1.27)) (justify left bottom) hide)
    )
    (pin "1")
    (pin "2")
    (instances
      (project "sdi-mipi-bridge"
        (path ""
          (reference "C34") (unit 1)
        )
      )
    )
  )

  (symbol (lib_id "sdi-mipi-bridge:C_10n_0402") (at 144.78 311.15 90) (unit 1)
    (in_bom yes) (on_board yes) (dnp no) (fields_autoplaced)
    (property "Reference" "C21" (at 147.32 307.3335 90)
      (effects (font (size 1.27 1.27)) (justify right))
    )
    (property "Value" "C_10n_0402" (at 154.94 290.83 0)
      (effects (font (size 1.27 1.27) (thickness 0.15)) (justify left bottom) hide)
    )
    (property "Footprint" "sdi-mipi-bridge-footprints:C_0402_1005Metric" (at 157.48 290.83 0)
      (effects (font (size 1.27 1.27) (thickness 0.15)) (justify left bottom) hide)
    )
    (property "Datasheet" "https://search.murata.co.jp/Ceramy/image/img/A01X/G101/ENG/GRM155R71H103KA88-01.pdf" (at 160.02 290.83 0)
      (effects (font (size 1.27 1.27) (thickness 0.15)) (justify left bottom) hide)
    )
    (property "Manufacturer" "Murata" (at 165.1 290.83 0)
      (effects (font (size 1.27 1.27) (thickness 0.15)) (justify left bottom) hide)
    )
    (property "MPN" "GRM155R71H103KA88D" (at 162.56 290.83 0)
      (effects (font (size 1.27 1.27) (thickness 0.15)) (justify left bottom) hide)
    )
    (property "Val" "10n" (at 147.32 309.8735 90)
      (effects (font (size 1.27 1.27) (thickness 0.15)) (justify right))
    )
    (property "License" "Apache-2.0" (at 167.64 290.83 0)
      (effects (font (size 1.27 1.27) (thickness 0.15)) (justify left bottom) hide)
    )
    (property "Author" "Antmicro" (at 170.18 290.83 0)
      (effects (font (size 1.27 1.27) (thickness 0.15)) (justify left bottom) hide)
    )
    (property "Voltage" "50V" (at 172.72 290.83 0)
      (effects (font (size 1.27 1.27)) (justify left bottom) hide)
    )
    (property "Dielectric" "X7R" (at 175.26 290.83 0)
      (effects (font (size 1.27 1.27)) (justify left bottom) hide)
    )
    (pin "1")
    (pin "2")
    (instances
      (project "sdi-mipi-bridge"
        (path ""
          (reference "C21") (unit 1)
        )
      )
    )
  )

  (symbol (lib_id "sdi-mipi-bridge:C_1u_0402") (at 152.4 311.15 90) (unit 1)
    (in_bom yes) (on_board yes) (dnp no) (fields_autoplaced)
    (property "Reference" "C26" (at 154.94 307.3335 90)
      (effects (font (size 1.27 1.27)) (justify right))
    )
    (property "Value" "C_1u_0402" (at 162.56 290.83 0)
      (effects (font (size 1.27 1.27) (thickness 0.15)) (justify left bottom) hide)
    )
    (property "Footprint" "sdi-mipi-bridge-footprints:C_0402_1005Metric" (at 165.1 290.83 0)
      (effects (font (size 1.27 1.27) (thickness 0.15)) (justify left bottom) hide)
    )
    (property "Datasheet" " " (at 167.64 290.83 0)
      (effects (font (size 1.27 1.27) (thickness 0.15)) (justify left bottom) hide)
    )
    (property "Manufacturer" "TDK" (at 172.72 290.83 0)
      (effects (font (size 1.27 1.27) (thickness 0.15)) (justify left bottom) hide)
    )
    (property "MPN" "C1005X6S1A105K050BC" (at 170.18 290.83 0)
      (effects (font (size 1.27 1.27) (thickness 0.15)) (justify left bottom) hide)
    )
    (property "Val" "1u" (at 154.94 309.8735 90)
      (effects (font (size 1.27 1.27) (thickness 0.15)) (justify right))
    )
    (property "License" "Apache-2.0" (at 175.26 290.83 0)
      (effects (font (size 1.27 1.27) (thickness 0.15)) (justify left bottom) hide)
    )
    (property "Author" "Antmicro" (at 177.8 290.83 0)
      (effects (font (size 1.27 1.27) (thickness 0.15)) (justify left bottom) hide)
    )
    (property "Voltage" "" (at 180.34 290.83 0)
      (effects (font (size 1.27 1.27)) (justify left bottom) hide)
    )
    (property "Dielectric" "" (at 182.88 290.83 0)
      (effects (font (size 1.27 1.27)) (justify left bottom) hide)
    )
    (pin "1")
    (pin "2")
    (instances
      (project "sdi-mipi-bridge"
        (path ""
          (reference "C26") (unit 1)
        )
      )
    )
  )

  (symbol (lib_id "sdi-mipi-bridge:R_0R_0402") (at 157.48 303.53 0) (unit 1)
    (in_bom yes) (on_board yes) (dnp no) (fields_autoplaced)
    (property "Reference" "R24" (at 160.02 297.18 0)
      (effects (font (size 1.27 1.27)))
    )
    (property "Value" "R_0R_0402" (at 177.8 316.23 0)
      (effects (font (size 1.27 1.27) (thickness 0.15)) (justify left bottom) hide)
    )
    (property "Footprint" "sdi-mipi-bridge-footprints:R_0402_1005Metric" (at 177.8 318.77 0)
      (effects (font (size 1.27 1.27) (thickness 0.15)) (justify left bottom) hide)
    )
    (property "Datasheet" "https://industrial.panasonic.com/cdbs/www-data/pdf/RDA0000/AOA0000C301.pdf" (at 177.8 321.31 0)
      (effects (font (size 1.27 1.27) (thickness 0.15)) (justify left bottom) hide)
    )
    (property "Manufacturer" "Panasonic" (at 177.8 326.39 0)
      (effects (font (size 1.27 1.27) (thickness 0.15)) (justify left bottom) hide)
    )
    (property "MPN" "ERJ2GE0R00X" (at 177.8 323.85 0)
      (effects (font (size 1.27 1.27) (thickness 0.15)) (justify left bottom) hide)
    )
    (property "Val" "0R" (at 160.02 299.72 0)
      (effects (font (size 1.27 1.27) (thickness 0.15)))
    )
    (property "License" "Apache-2.0" (at 177.8 328.93 0)
      (effects (font (size 1.27 1.27) (thickness 0.15)) (justify left bottom) hide)
    )
    (property "Author" "Antmicro" (at 177.8 331.47 0)
      (effects (font (size 1.27 1.27) (thickness 0.15)) (justify left bottom) hide)
    )
    (property "Tolerance" "~" (at 177.8 313.69 0)
      (effects (font (size 1.27 1.27)) (justify left bottom) hide)
    )
    (property "Current" "1A" (at 177.8 334.01 0)
      (effects (font (size 1.27 1.27) (thickness 0.15)) (justify left bottom) hide)
    )
    (pin "1")
    (pin "2")
    (instances
      (project "sdi-mipi-bridge"
        (path ""
          (reference "R24") (unit 1)
        )
      )
    )
  )

  (symbol (lib_id "sdi-mipi-bridge:GNDREF") (at 152.4 311.15 0) (unit 1)
    (in_bom yes) (on_board yes) (dnp no)
    (property "Reference" "#PWR023" (at 152.4 317.5 0)
      (effects (font (size 1.27 1.27)) hide)
    )
    (property "Value" "GNDREF" (at 152.4 314.96 0)
      (effects (font (size 1.27 1.27)))
    )
    (property "Footprint" "" (at 152.4 311.15 0)
      (effects (font (size 1.27 1.27)) hide)
    )
    (property "Datasheet" "" (at 152.4 311.15 0)
      (effects (font (size 1.27 1.27)) hide)
    )
    (pin "1")
    (instances
      (project "sdi-mipi-bridge"
        (path ""
          (reference "#PWR023") (unit 1)
        )
      )
    )
  )

  (symbol (lib_id "sdi-mipi-bridge:C_1u_0402") (at 167.64 311.15 90) (unit 1)
    (in_bom yes) (on_board yes) (dnp no) (fields_autoplaced)
    (property "Reference" "C30" (at 170.18 307.3335 90)
      (effects (font (size 1.27 1.27)) (justify right))
    )
    (property "Value" "C_1u_0402" (at 177.8 290.83 0)
      (effects (font (size 1.27 1.27) (thickness 0.15)) (justify left bottom) hide)
    )
    (property "Footprint" "sdi-mipi-bridge-footprints:C_0402_1005Metric" (at 180.34 290.83 0)
      (effects (font (size 1.27 1.27) (thickness 0.15)) (justify left bottom) hide)
    )
    (property "Datasheet" " " (at 182.88 290.83 0)
      (effects (font (size 1.27 1.27) (thickness 0.15)) (justify left bottom) hide)
    )
    (property "Manufacturer" "TDK" (at 187.96 290.83 0)
      (effects (font (size 1.27 1.27) (thickness 0.15)) (justify left bottom) hide)
    )
    (property "MPN" "C1005X6S1A105K050BC" (at 185.42 290.83 0)
      (effects (font (size 1.27 1.27) (thickness 0.15)) (justify left bottom) hide)
    )
    (property "Val" "1u" (at 170.18 309.8735 90)
      (effects (font (size 1.27 1.27) (thickness 0.15)) (justify right))
    )
    (property "License" "Apache-2.0" (at 190.5 290.83 0)
      (effects (font (size 1.27 1.27) (thickness 0.15)) (justify left bottom) hide)
    )
    (property "Author" "Antmicro" (at 193.04 290.83 0)
      (effects (font (size 1.27 1.27) (thickness 0.15)) (justify left bottom) hide)
    )
    (property "Voltage" "" (at 195.58 290.83 0)
      (effects (font (size 1.27 1.27)) (justify left bottom) hide)
    )
    (property "Dielectric" "" (at 198.12 290.83 0)
      (effects (font (size 1.27 1.27)) (justify left bottom) hide)
    )
    (pin "1")
    (pin "2")
    (instances
      (project "sdi-mipi-bridge"
        (path ""
          (reference "C30") (unit 1)
        )
      )
    )
  )

  (symbol (lib_id "sdi-mipi-bridge:GNDA") (at 175.26 311.15 0) (unit 1)
    (in_bom yes) (on_board yes) (dnp no)
    (property "Reference" "#PWR029" (at 175.26 317.5 0)
      (effects (font (size 1.27 1.27)) hide)
    )
    (property "Value" "GNDA" (at 175.26 314.96 0)
      (effects (font (size 1.27 1.27)))
    )
    (property "Footprint" "" (at 175.26 311.15 0)
      (effects (font (size 1.27 1.27)) hide)
    )
    (property "Datasheet" "" (at 175.26 311.15 0)
      (effects (font (size 1.27 1.27)) hide)
    )
    (pin "1")
    (instances
      (project "sdi-mipi-bridge"
        (path ""
          (reference "#PWR029") (unit 1)
        )
      )
    )
  )

  (symbol (lib_id "sdi-mipi-bridge:R_100R_0402") (at 346.71 236.22 0) (mirror y) (unit 1)
    (in_bom yes) (on_board yes) (dnp no)
    (property "Reference" "R93" (at 344.17 233.68 0)
      (effects (font (size 1.27 1.27)))
    )
    (property "Value" "R_100R_0402" (at 346.71 240.03 0)
      (effects (font (size 1.27 1.27) (thickness 0.15)) (justify left bottom) hide)
    )
    (property "Footprint" "sdi-mipi-bridge-footprints:R_0402_1005Metric" (at 341.63 231.14 0)
      (effects (font (size 1.27 1.27) (thickness 0.15)) (justify left bottom) hide)
    )
    (property "Datasheet" "https://www.bourns.com/docs/product-datasheets/cr.pdf" (at 346.71 236.22 0)
      (effects (font (size 1.27 1.27) (thickness 0.15)) (justify left bottom) hide)
    )
    (property "Manufacturer" "Bourns" (at 341.63 226.06 0)
      (effects (font (size 1.27 1.27) (thickness 0.15)) (justify left bottom) hide)
    )
    (property "MPN" "CR0402-FX-1000GLF" (at 341.63 228.6 0)
      (effects (font (size 1.27 1.27) (thickness 0.15)) (justify left bottom) hide)
    )
    (property "Val" "100R" (at 344.17 238.76 0)
      (effects (font (size 1.27 1.27) (thickness 0.15)))
    )
    (property "License" "Apache-2.0" (at 326.39 261.62 0)
      (effects (font (size 1.27 1.27) (thickness 0.15)) (justify left bottom) hide)
    )
    (property "Author" "Antmicro" (at 326.39 264.16 0)
      (effects (font (size 1.27 1.27) (thickness 0.15)) (justify left bottom) hide)
    )
    (property "Tolerance" "1%" (at 326.39 246.38 0)
      (effects (font (size 1.27 1.27)) (justify left bottom) hide)
    )
    (pin "1")
    (pin "2")
    (instances
      (project "sdi-mipi-bridge"
        (path ""
          (reference "R93") (unit 1)
        )
      )
    )
  )

  (symbol (lib_id "sdi-mipi-bridge:LED_G_0603_LG_L29K-G2J1-24-Z") (at 354.33 236.22 0) (mirror x) (unit 1)
    (in_bom yes) (on_board yes) (dnp no)
    (property "Reference" "D4" (at 358.14 233.68 0)
      (effects (font (size 1.27 1.27)))
    )
    (property "Value" "LED_G_0603_LG_L29K-G2J1-24-Z" (at 361.95 242.57 0)
      (effects (font (size 1.27 1.27) (thickness 0.15)) (justify left bottom) hide)
    )
    (property "Footprint" "sdi-mipi-bridge-footprints:LED_0603_1608Metric_G" (at 359.41 241.3 0)
      (effects (font (size 1.27 1.27) (thickness 0.15)) (justify left bottom) hide)
    )
    (property "Datasheet" "https://dammedia.osram.info/media/resource/hires/osram-dam-2493945/LG%20L29K.pdf" (at 359.41 243.84 0)
      (effects (font (size 1.27 1.27) (thickness 0.15)) (justify left bottom) hide)
    )
    (property "MPN" "LG L29K-G2J1-24-Z" (at 358.14 240.03 0)
      (effects (font (size 1.27 1.27) (thickness 0.15)))
    )
    (property "Manufacturer" "Osram" (at 359.41 264.16 0)
      (effects (font (size 1.27 1.27) (thickness 0.15)) (justify left bottom) hide)
    )
    (property "Author" "Antmicro" (at 377.19 215.9 0)
      (effects (font (size 1.27 1.27) (thickness 0.15)) (justify left bottom) hide)
    )
    (property "License" "Apache-2.0" (at 377.19 213.36 0)
      (effects (font (size 1.27 1.27) (thickness 0.15)) (justify left bottom) hide)
    )
    (pin "1")
    (pin "2")
    (instances
      (project "sdi-mipi-bridge"
        (path ""
          (reference "D4") (unit 1)
        )
      )
    )
  )

  (symbol (lib_id "sdi-mipi-bridge:C_10n_0402") (at 99.06 139.7 90) (unit 1)
    (in_bom yes) (on_board yes) (dnp no) (fields_autoplaced)
    (property "Reference" "C18" (at 101.6 135.8835 90)
      (effects (font (size 1.27 1.27)) (justify right))
    )
    (property "Value" "C_10n_0402" (at 109.22 119.38 0)
      (effects (font (size 1.27 1.27) (thickness 0.15)) (justify left bottom) hide)
    )
    (property "Footprint" "sdi-mipi-bridge-footprints:C_0402_1005Metric" (at 111.76 119.38 0)
      (effects (font (size 1.27 1.27) (thickness 0.15)) (justify left bottom) hide)
    )
    (property "Datasheet" "https://search.murata.co.jp/Ceramy/image/img/A01X/G101/ENG/GRM155R71H103KA88-01.pdf" (at 114.3 119.38 0)
      (effects (font (size 1.27 1.27) (thickness 0.15)) (justify left bottom) hide)
    )
    (property "Manufacturer" "Murata" (at 119.38 119.38 0)
      (effects (font (size 1.27 1.27) (thickness 0.15)) (justify left bottom) hide)
    )
    (property "MPN" "GRM155R71H103KA88D" (at 116.84 119.38 0)
      (effects (font (size 1.27 1.27) (thickness 0.15)) (justify left bottom) hide)
    )
    (property "Val" "10n" (at 101.6 138.4235 90)
      (effects (font (size 1.27 1.27) (thickness 0.15)) (justify right))
    )
    (property "License" "Apache-2.0" (at 121.92 119.38 0)
      (effects (font (size 1.27 1.27) (thickness 0.15)) (justify left bottom) hide)
    )
    (property "Author" "Antmicro" (at 124.46 119.38 0)
      (effects (font (size 1.27 1.27) (thickness 0.15)) (justify left bottom) hide)
    )
    (property "Voltage" "50V" (at 127 119.38 0)
      (effects (font (size 1.27 1.27)) (justify left bottom) hide)
    )
    (property "Dielectric" "X7R" (at 129.54 119.38 0)
      (effects (font (size 1.27 1.27)) (justify left bottom) hide)
    )
    (pin "1")
    (pin "2")
    (instances
      (project "sdi-mipi-bridge"
        (path ""
          (reference "C18") (unit 1)
        )
      )
    )
  )

  (symbol (lib_id "sdi-mipi-bridge:VDD") (at 175.26 300.99 0) (unit 1)
    (in_bom yes) (on_board yes) (dnp no)
    (property "Reference" "#PWR0110" (at 175.26 304.8 0)
      (effects (font (size 1.27 1.27)) hide)
    )
    (property "Value" "VDD" (at 175.6918 296.5958 0)
      (effects (font (size 1.27 1.27)) hide)
    )
    (property "Footprint" "" (at 175.26 300.99 0)
      (effects (font (size 1.27 1.27)) hide)
    )
    (property "Datasheet" "" (at 175.26 300.99 0)
      (effects (font (size 1.27 1.27)) hide)
    )
    (property "Voltage" "CD_VDD" (at 175.6918 296.5958 0)
      (effects (font (size 1.27 1.27)))
    )
    (pin "1")
    (instances
      (project "sdi-mipi-bridge"
        (path ""
          (reference "#PWR0110") (unit 1)
        )
      )
    )
  )

  (symbol (lib_id "sdi-mipi-bridge:TP_1mm_SMD") (at 134.62 156.21 0) (unit 1)
    (in_bom yes) (on_board yes) (dnp no) (fields_autoplaced)
    (property "Reference" "TP18" (at 139.7 156.2099 0)
      (effects (font (size 1.27 1.27)) (justify left))
    )
    (property "Value" "TP_1mm_SMD" (at 149.86 163.83 0)
      (effects (font (size 1.27 1.27) (thickness 0.15)) (justify left bottom) hide)
    )
    (property "Footprint" "sdi-mipi-bridge-footprints:Testpoint_smd_1mm" (at 149.86 166.37 0)
      (effects (font (size 1.27 1.27) (thickness 0.15)) (justify left bottom) hide)
    )
    (property "Datasheet" "" (at 149.86 168.91 0)
      (effects (font (size 1.27 1.27) (thickness 0.15)) (justify left bottom) hide)
    )
    (property "MPN" "" (at 134.62 156.21 0)
      (effects (font (size 1.27 1.27)) hide)
    )
    (property "Manufacturer" "" (at 134.62 156.21 0)
      (effects (font (size 1.27 1.27)) hide)
    )
    (property "Author" "Antmicro" (at 149.86 171.45 0)
      (effects (font (size 1.27 1.27) (thickness 0.15)) (justify left bottom) hide)
    )
    (property "License" "Apache-2.0" (at 149.86 173.99 0)
      (effects (font (size 1.27 1.27) (thickness 0.15)) (justify left bottom) hide)
    )
    (pin "1")
    (instances
      (project "sdi-mipi-bridge"
        (path ""
          (reference "TP18") (unit 1)
        )
      )
    )
  )

  (symbol (lib_id "sdi-mipi-bridge:GNDA") (at 99.06 139.7 0) (unit 1)
    (in_bom yes) (on_board yes) (dnp no)
    (property "Reference" "#PWR017" (at 99.06 146.05 0)
      (effects (font (size 1.27 1.27)) hide)
    )
    (property "Value" "GNDA" (at 99.06 143.51 0)
      (effects (font (size 1.27 1.27)))
    )
    (property "Footprint" "" (at 99.06 139.7 0)
      (effects (font (size 1.27 1.27)) hide)
    )
    (property "Datasheet" "" (at 99.06 139.7 0)
      (effects (font (size 1.27 1.27)) hide)
    )
    (pin "1")
    (instances
      (project "sdi-mipi-bridge"
        (path ""
          (reference "#PWR017") (unit 1)
        )
      )
    )
  )

  (symbol (lib_id "sdi-mipi-bridge:GNDREF") (at 519.43 68.58 0) (unit 1)
    (in_bom yes) (on_board yes) (dnp no)
    (property "Reference" "#PWR068" (at 519.43 74.93 0)
      (effects (font (size 1.27 1.27)) hide)
    )
    (property "Value" "GNDREF" (at 519.557 72.9742 0)
      (effects (font (size 1.27 1.27)))
    )
    (property "Footprint" "" (at 519.43 68.58 0)
      (effects (font (size 1.27 1.27)) hide)
    )
    (property "Datasheet" "" (at 519.43 68.58 0)
      (effects (font (size 1.27 1.27)) hide)
    )
    (pin "1")
    (instances
      (project "sdi-mipi-bridge"
        (path ""
          (reference "#PWR068") (unit 1)
        )
      )
    )
  )

  (symbol (lib_id "sdi-mipi-bridge:R_75R_0603") (at 170.18 160.02 0) (unit 1)
    (in_bom yes) (on_board yes) (dnp no)
    (property "Reference" "R17" (at 172.72 154.94 0)
      (effects (font (size 1.27 1.27)))
    )
    (property "Value" "R_75R_0603" (at 190.5 172.72 0)
      (effects (font (size 1.27 1.27) (thickness 0.15)) (justify left bottom) hide)
    )
    (property "Footprint" "sdi-mipi-bridge-footprints:R_0603_1608Metric" (at 190.5 175.26 0)
      (effects (font (size 1.27 1.27) (thickness 0.15)) (justify left bottom) hide)
    )
    (property "Datasheet" "https://www.bourns.com/docs/product-datasheets/cr.pdf" (at 190.5 177.8 0)
      (effects (font (size 1.27 1.27) (thickness 0.15)) (justify left bottom) hide)
    )
    (property "Manufacturer" "Bourns" (at 190.5 182.88 0)
      (effects (font (size 1.27 1.27) (thickness 0.15)) (justify left bottom) hide)
    )
    (property "MPN" "CR0603-FX-75R0ELF" (at 190.5 180.34 0)
      (effects (font (size 1.27 1.27) (thickness 0.15)) (justify left bottom) hide)
    )
    (property "Val" "75R" (at 172.72 157.48 0)
      (effects (font (size 1.27 1.27) (thickness 0.15)))
    )
    (property "License" "Apache-2.0" (at 190.5 185.42 0)
      (effects (font (size 1.27 1.27) (thickness 0.15)) (justify left bottom) hide)
    )
    (property "Author" "Antmicro" (at 190.5 187.96 0)
      (effects (font (size 1.27 1.27) (thickness 0.15)) (justify left bottom) hide)
    )
    (property "Tolerance" "1%" (at 190.5 170.18 0)
      (effects (font (size 1.27 1.27)) (justify left bottom) hide)
    )
    (pin "1")
    (pin "2")
    (instances
      (project "sdi-mipi-bridge"
        (path ""
          (reference "R17") (unit 1)
        )
      )
    )
  )

  (symbol (lib_id "sdi-mipi-bridge:Conn_BNC_031-70526-21") (at 189.23 160.02 0) (unit 1)
    (in_bom yes) (on_board yes) (dnp no) (fields_autoplaced)
    (property "Reference" "J1" (at 198.12 160.3767 0)
      (effects (font (size 1.27 1.27)) (justify left))
    )
    (property "Value" "Conn_BNC_031-70526-21" (at 198.12 161.6466 0)
      (effects (font (size 1.27 1.27) (thickness 0.15)) (justify left) hide)
    )
    (property "Footprint" "sdi-mipi-bridge-footprints:Conn_BNC_031-70526-21" (at 209.55 170.18 0)
      (effects (font (size 1.27 1.27) (thickness 0.15)) (justify left bottom) hide)
    )
    (property "Datasheet" "https://www.farnell.com/cad/2305565.pdf?_ga=2.190633003.1014497200.1574067480-156563690.1566371002&_gac=1.57062104.1572875319.Cj0KCQiAtf_tBRDtARIsAIbAKe0A1M5y_jdFCiNLNrHM5L2GjmDvn_4qnRvhHAD9jBdL9AmoMNThLCoaAjhJEALw_wcB" (at 209.55 172.72 0)
      (effects (font (size 1.27 1.27) (thickness 0.15)) (justify left bottom) hide)
    )
    (property "MPN" "031-70526-21" (at 209.55 175.26 0)
      (effects (font (size 1.27 1.27) (thickness 0.15)) (justify left bottom) hide)
    )
    (property "Manufacturer" "Amphenol" (at 209.55 177.8 0)
      (effects (font (size 1.27 1.27) (thickness 0.15)) (justify left bottom) hide)
    )
    (property "Author" "Antmicro" (at 209.55 180.34 0)
      (effects (font (size 1.27 1.27) (thickness 0.15)) (justify left bottom) hide)
    )
    (property "License" "Apache-2.0" (at 209.55 182.88 0)
      (effects (font (size 1.27 1.27) (thickness 0.15)) (justify left bottom) hide)
    )
    (pin "1")
    (pin "2")
    (instances
      (project "sdi-mipi-bridge"
        (path ""
          (reference "J1") (unit 1)
        )
      )
    )
  )

  (symbol (lib_id "sdi-mipi-bridge:+3V3") (at 154.94 346.71 0) (unit 1)
    (in_bom yes) (on_board yes) (dnp no)
    (property "Reference" "#PWR0114" (at 154.94 350.52 0)
      (effects (font (size 1.27 1.27)) hide)
    )
    (property "Value" "+3V3" (at 155.321 342.3158 0)
      (effects (font (size 1.27 1.27)))
    )
    (property "Footprint" "" (at 154.94 346.71 0)
      (effects (font (size 1.27 1.27)) hide)
    )
    (property "Datasheet" "" (at 154.94 346.71 0)
      (effects (font (size 1.27 1.27)) hide)
    )
    (property "Author" "Antmicro" (at 170.18 354.33 0)
      (effects (font (size 1.27 1.27) (thickness 0.15)) (justify left bottom) hide)
    )
    (property "License" "Apache-2.0" (at 170.18 356.87 0)
      (effects (font (size 1.27 1.27) (thickness 0.15)) (justify left bottom) hide)
    )
    (pin "1")
    (instances
      (project "sdi-mipi-bridge"
        (path ""
          (reference "#PWR0114") (unit 1)
        )
      )
    )
  )

  (symbol (lib_id "sdi-mipi-bridge:+3V3") (at 144.78 300.99 0) (unit 1)
    (in_bom yes) (on_board yes) (dnp no)
    (property "Reference" "#PWR0120" (at 144.78 304.8 0)
      (effects (font (size 1.27 1.27)) hide)
    )
    (property "Value" "+3V3" (at 145.161 296.5958 0)
      (effects (font (size 1.27 1.27)))
    )
    (property "Footprint" "" (at 144.78 300.99 0)
      (effects (font (size 1.27 1.27)) hide)
    )
    (property "Datasheet" "" (at 144.78 300.99 0)
      (effects (font (size 1.27 1.27)) hide)
    )
    (property "Author" "Antmicro" (at 160.02 308.61 0)
      (effects (font (size 1.27 1.27) (thickness 0.15)) (justify left bottom) hide)
    )
    (property "License" "Apache-2.0" (at 160.02 311.15 0)
      (effects (font (size 1.27 1.27) (thickness 0.15)) (justify left bottom) hide)
    )
    (pin "1")
    (instances
      (project "sdi-mipi-bridge"
        (path ""
          (reference "#PWR0120") (unit 1)
        )
      )
    )
  )

  (symbol (lib_id "sdi-mipi-bridge:+3V3") (at 228.6 218.44 0) (unit 1)
    (in_bom yes) (on_board yes) (dnp no)
    (property "Reference" "#PWR0121" (at 228.6 222.25 0)
      (effects (font (size 1.27 1.27)) hide)
    )
    (property "Value" "+3V3" (at 228.981 214.0458 0)
      (effects (font (size 1.27 1.27)))
    )
    (property "Footprint" "" (at 228.6 218.44 0)
      (effects (font (size 1.27 1.27)) hide)
    )
    (property "Datasheet" "" (at 228.6 218.44 0)
      (effects (font (size 1.27 1.27)) hide)
    )
    (property "Author" "Antmicro" (at 243.84 226.06 0)
      (effects (font (size 1.27 1.27) (thickness 0.15)) (justify left bottom) hide)
    )
    (property "License" "Apache-2.0" (at 243.84 228.6 0)
      (effects (font (size 1.27 1.27) (thickness 0.15)) (justify left bottom) hide)
    )
    (pin "1")
    (instances
      (project "sdi-mipi-bridge"
        (path ""
          (reference "#PWR0121") (unit 1)
        )
      )
    )
  )

  (symbol (lib_id "sdi-mipi-bridge:+3V3") (at 220.98 368.3 0) (unit 1)
    (in_bom yes) (on_board yes) (dnp no)
    (property "Reference" "#PWR0122" (at 220.98 372.11 0)
      (effects (font (size 1.27 1.27)) hide)
    )
    (property "Value" "+3V3" (at 221.361 363.9058 0)
      (effects (font (size 1.27 1.27)))
    )
    (property "Footprint" "" (at 220.98 368.3 0)
      (effects (font (size 1.27 1.27)) hide)
    )
    (property "Datasheet" "" (at 220.98 368.3 0)
      (effects (font (size 1.27 1.27)) hide)
    )
    (property "Author" "Antmicro" (at 236.22 375.92 0)
      (effects (font (size 1.27 1.27) (thickness 0.15)) (justify left bottom) hide)
    )
    (property "License" "Apache-2.0" (at 236.22 378.46 0)
      (effects (font (size 1.27 1.27) (thickness 0.15)) (justify left bottom) hide)
    )
    (pin "1")
    (instances
      (project "sdi-mipi-bridge"
        (path ""
          (reference "#PWR0122") (unit 1)
        )
      )
    )
  )

  (symbol (lib_id "sdi-mipi-bridge:+3V3") (at 36.83 226.06 0) (unit 1)
    (in_bom yes) (on_board yes) (dnp no)
    (property "Reference" "#PWR0123" (at 36.83 229.87 0)
      (effects (font (size 1.27 1.27)) hide)
    )
    (property "Value" "+3V3" (at 37.211 221.6658 0)
      (effects (font (size 1.27 1.27)))
    )
    (property "Footprint" "" (at 36.83 226.06 0)
      (effects (font (size 1.27 1.27)) hide)
    )
    (property "Datasheet" "" (at 36.83 226.06 0)
      (effects (font (size 1.27 1.27)) hide)
    )
    (property "Author" "Antmicro" (at 52.07 233.68 0)
      (effects (font (size 1.27 1.27) (thickness 0.15)) (justify left bottom) hide)
    )
    (property "License" "Apache-2.0" (at 52.07 236.22 0)
      (effects (font (size 1.27 1.27) (thickness 0.15)) (justify left bottom) hide)
    )
    (pin "1")
    (instances
      (project "sdi-mipi-bridge"
        (path ""
          (reference "#PWR0123") (unit 1)
        )
      )
    )
  )

  (symbol (lib_id "sdi-mipi-bridge:+3V3") (at 43.18 152.4 0) (unit 1)
    (in_bom yes) (on_board yes) (dnp no)
    (property "Reference" "#PWR0124" (at 43.18 156.21 0)
      (effects (font (size 1.27 1.27)) hide)
    )
    (property "Value" "+3V3" (at 43.561 148.0058 0)
      (effects (font (size 1.27 1.27)))
    )
    (property "Footprint" "" (at 43.18 152.4 0)
      (effects (font (size 1.27 1.27)) hide)
    )
    (property "Datasheet" "" (at 43.18 152.4 0)
      (effects (font (size 1.27 1.27)) hide)
    )
    (property "Author" "Antmicro" (at 58.42 160.02 0)
      (effects (font (size 1.27 1.27) (thickness 0.15)) (justify left bottom) hide)
    )
    (property "License" "Apache-2.0" (at 58.42 162.56 0)
      (effects (font (size 1.27 1.27) (thickness 0.15)) (justify left bottom) hide)
    )
    (pin "1")
    (instances
      (project "sdi-mipi-bridge"
        (path ""
          (reference "#PWR0124") (unit 1)
        )
      )
    )
  )

  (symbol (lib_id "sdi-mipi-bridge:+3V3") (at 17.78 118.11 0) (unit 1)
    (in_bom yes) (on_board yes) (dnp no)
    (property "Reference" "#PWR0125" (at 17.78 121.92 0)
      (effects (font (size 1.27 1.27)) hide)
    )
    (property "Value" "+3V3" (at 18.161 113.7158 0)
      (effects (font (size 1.27 1.27)))
    )
    (property "Footprint" "" (at 17.78 118.11 0)
      (effects (font (size 1.27 1.27)) hide)
    )
    (property "Datasheet" "" (at 17.78 118.11 0)
      (effects (font (size 1.27 1.27)) hide)
    )
    (property "Author" "Antmicro" (at 33.02 125.73 0)
      (effects (font (size 1.27 1.27) (thickness 0.15)) (justify left bottom) hide)
    )
    (property "License" "Apache-2.0" (at 33.02 128.27 0)
      (effects (font (size 1.27 1.27) (thickness 0.15)) (justify left bottom) hide)
    )
    (pin "1")
    (instances
      (project "sdi-mipi-bridge"
        (path ""
          (reference "#PWR0125") (unit 1)
        )
      )
    )
  )

  (symbol (lib_id "sdi-mipi-bridge:+3V3") (at 534.67 237.49 0) (unit 1)
    (in_bom yes) (on_board yes) (dnp no)
    (property "Reference" "#PWR0126" (at 534.67 241.3 0)
      (effects (font (size 1.27 1.27)) hide)
    )
    (property "Value" "+3V3" (at 535.051 233.0958 0)
      (effects (font (size 1.27 1.27)))
    )
    (property "Footprint" "" (at 549.91 245.11 0)
      (effects (font (size 1.27 1.27) (thickness 0.15)) (justify left bottom) hide)
    )
    (property "Datasheet" "" (at 549.91 247.65 0)
      (effects (font (size 1.27 1.27) (thickness 0.15)) (justify left bottom) hide)
    )
    (property "Author" "Antmicro" (at 549.91 245.11 0)
      (effects (font (size 1.27 1.27) (thickness 0.15)) (justify left bottom) hide)
    )
    (property "License" "Apache-2.0" (at 549.91 247.65 0)
      (effects (font (size 1.27 1.27) (thickness 0.15)) (justify left bottom) hide)
    )
    (pin "1")
    (instances
      (project "sdi-mipi-bridge"
        (path ""
          (reference "#PWR0126") (unit 1)
        )
      )
    )
  )

  (symbol (lib_id "sdi-mipi-bridge:+3V3") (at 543.56 146.05 0) (unit 1)
    (in_bom yes) (on_board yes) (dnp no)
    (property "Reference" "#PWR0127" (at 543.56 149.86 0)
      (effects (font (size 1.27 1.27)) hide)
    )
    (property "Value" "+3.3V" (at 543.941 141.6558 0)
      (effects (font (size 1.27 1.27)))
    )
    (property "Footprint" "" (at 543.56 146.05 0)
      (effects (font (size 1.27 1.27)) hide)
    )
    (property "Datasheet" "" (at 543.56 146.05 0)
      (effects (font (size 1.27 1.27)) hide)
    )
    (property "Author" "Antmicro" (at 558.8 153.67 0)
      (effects (font (size 1.27 1.27) (thickness 0.15)) (justify left bottom) hide)
    )
    (property "License" "Apache-2.0" (at 558.8 156.21 0)
      (effects (font (size 1.27 1.27) (thickness 0.15)) (justify left bottom) hide)
    )
    (pin "1")
    (instances
      (project "sdi-mipi-bridge"
        (path ""
          (reference "#PWR0127") (unit 1)
        )
      )
    )
  )

  (symbol (lib_id "sdi-mipi-bridge:+3V3") (at 506.73 39.37 0) (unit 1)
    (in_bom yes) (on_board yes) (dnp no)
    (property "Reference" "#PWR0128" (at 506.73 43.18 0)
      (effects (font (size 1.27 1.27)) hide)
    )
    (property "Value" "+3V3" (at 507.111 34.9758 0)
      (effects (font (size 1.27 1.27)))
    )
    (property "Footprint" "" (at 506.73 39.37 0)
      (effects (font (size 1.27 1.27)) hide)
    )
    (property "Datasheet" "" (at 506.73 39.37 0)
      (effects (font (size 1.27 1.27)) hide)
    )
    (property "Author" "Antmicro" (at 521.97 46.99 0)
      (effects (font (size 1.27 1.27) (thickness 0.15)) (justify left bottom) hide)
    )
    (property "License" "Apache-2.0" (at 521.97 49.53 0)
      (effects (font (size 1.27 1.27) (thickness 0.15)) (justify left bottom) hide)
    )
    (pin "1")
    (instances
      (project "sdi-mipi-bridge"
        (path ""
          (reference "#PWR0128") (unit 1)
        )
      )
    )
  )

  (symbol (lib_id "sdi-mipi-bridge:+3V3") (at 427.99 148.59 0) (unit 1)
    (in_bom yes) (on_board yes) (dnp no)
    (property "Reference" "#PWR0130" (at 427.99 152.4 0)
      (effects (font (size 1.27 1.27)) hide)
    )
    (property "Value" "+3V3" (at 428.371 144.1958 0)
      (effects (font (size 1.27 1.27)))
    )
    (property "Footprint" "" (at 427.99 148.59 0)
      (effects (font (size 1.27 1.27)) hide)
    )
    (property "Datasheet" "" (at 427.99 148.59 0)
      (effects (font (size 1.27 1.27)) hide)
    )
    (property "Author" "Antmicro" (at 443.23 156.21 0)
      (effects (font (size 1.27 1.27) (thickness 0.15)) (justify left bottom) hide)
    )
    (property "License" "Apache-2.0" (at 443.23 158.75 0)
      (effects (font (size 1.27 1.27) (thickness 0.15)) (justify left bottom) hide)
    )
    (pin "1")
    (instances
      (project "sdi-mipi-bridge"
        (path ""
          (reference "#PWR0130") (unit 1)
        )
      )
    )
  )

  (symbol (lib_id "sdi-mipi-bridge:R_75R_0603") (at 147.32 152.4 0) (mirror x) (unit 1)
    (in_bom yes) (on_board yes) (dnp no)
    (property "Reference" "R19" (at 149.86 149.86 0)
      (effects (font (size 1.27 1.27)))
    )
    (property "Value" "R_75R_0603" (at 167.64 139.7 0)
      (effects (font (size 1.27 1.27) (thickness 0.15)) (justify left bottom) hide)
    )
    (property "Footprint" "sdi-mipi-bridge-footprints:R_0603_1608Metric" (at 167.64 137.16 0)
      (effects (font (size 1.27 1.27) (thickness 0.15)) (justify left bottom) hide)
    )
    (property "Datasheet" "https://www.bourns.com/docs/product-datasheets/cr.pdf" (at 167.64 134.62 0)
      (effects (font (size 1.27 1.27) (thickness 0.15)) (justify left bottom) hide)
    )
    (property "Manufacturer" "Bourns" (at 167.64 129.54 0)
      (effects (font (size 1.27 1.27) (thickness 0.15)) (justify left bottom) hide)
    )
    (property "MPN" "CR0603-FX-75R0ELF" (at 167.64 132.08 0)
      (effects (font (size 1.27 1.27) (thickness 0.15)) (justify left bottom) hide)
    )
    (property "Val" "75R" (at 149.86 154.94 0)
      (effects (font (size 1.27 1.27) (thickness 0.15)))
    )
    (property "License" "Apache-2.0" (at 167.64 127 0)
      (effects (font (size 1.27 1.27) (thickness 0.15)) (justify left bottom) hide)
    )
    (property "Author" "Antmicro" (at 167.64 124.46 0)
      (effects (font (size 1.27 1.27) (thickness 0.15)) (justify left bottom) hide)
    )
    (property "Tolerance" "1%" (at 167.64 142.24 0)
      (effects (font (size 1.27 1.27)) (justify left bottom) hide)
    )
    (pin "1")
    (pin "2")
    (instances
      (project "sdi-mipi-bridge"
        (path ""
          (reference "R19") (unit 1)
        )
      )
    )
  )

  (symbol (lib_id "sdi-mipi-bridge:+3V3") (at 144.78 222.25 0) (unit 1)
    (in_bom yes) (on_board yes) (dnp no)
    (property "Reference" "#PWR0131" (at 144.78 226.06 0)
      (effects (font (size 1.27 1.27)) hide)
    )
    (property "Value" "+3V3" (at 145.161 217.8558 0)
      (effects (font (size 1.27 1.27)))
    )
    (property "Footprint" "" (at 144.78 222.25 0)
      (effects (font (size 1.27 1.27)) hide)
    )
    (property "Datasheet" "" (at 144.78 222.25 0)
      (effects (font (size 1.27 1.27)) hide)
    )
    (property "Author" "Antmicro" (at 160.02 229.87 0)
      (effects (font (size 1.27 1.27) (thickness 0.15)) (justify left bottom) hide)
    )
    (property "License" "Apache-2.0" (at 160.02 232.41 0)
      (effects (font (size 1.27 1.27) (thickness 0.15)) (justify left bottom) hide)
    )
    (pin "1")
    (instances
      (project "sdi-mipi-bridge"
        (path ""
          (reference "#PWR0131") (unit 1)
        )
      )
    )
  )

  (symbol (lib_id "sdi-mipi-bridge:R_0R_0402") (at 513.08 44.45 0) (unit 1)
    (in_bom yes) (on_board yes) (dnp no)
    (property "Reference" "R43" (at 511.81 43.18 0)
      (effects (font (size 1.27 1.27)))
    )
    (property "Value" "R_0R_0402" (at 533.4 57.15 0)
      (effects (font (size 1.27 1.27) (thickness 0.15)) (justify left bottom) hide)
    )
    (property "Footprint" "sdi-mipi-bridge-footprints:R_0402_1005Metric" (at 533.4 59.69 0)
      (effects (font (size 1.27 1.27) (thickness 0.15)) (justify left bottom) hide)
    )
    (property "Datasheet" "https://industrial.panasonic.com/cdbs/www-data/pdf/RDA0000/AOA0000C301.pdf" (at 533.4 62.23 0)
      (effects (font (size 1.27 1.27) (thickness 0.15)) (justify left bottom) hide)
    )
    (property "Manufacturer" "Panasonic" (at 533.4 67.31 0)
      (effects (font (size 1.27 1.27) (thickness 0.15)) (justify left bottom) hide)
    )
    (property "MPN" "ERJ2GE0R00X" (at 533.4 64.77 0)
      (effects (font (size 1.27 1.27) (thickness 0.15)) (justify left bottom) hide)
    )
    (property "Val" "0R" (at 519.43 43.18 0)
      (effects (font (size 1.27 1.27) (thickness 0.15)))
    )
    (property "License" "Apache-2.0" (at 533.4 69.85 0)
      (effects (font (size 1.27 1.27) (thickness 0.15)) (justify left bottom) hide)
    )
    (property "Author" "Antmicro" (at 533.4 72.39 0)
      (effects (font (size 1.27 1.27) (thickness 0.15)) (justify left bottom) hide)
    )
    (property "Tolerance" "~" (at 533.4 54.61 0)
      (effects (font (size 1.27 1.27)) (justify left bottom) hide)
    )
    (property "Current" "1A" (at 533.4 74.93 0)
      (effects (font (size 1.27 1.27) (thickness 0.15)) (justify left bottom) hide)
    )
    (pin "1")
    (pin "2")
    (instances
      (project "sdi-mipi-bridge"
        (path ""
          (reference "R43") (unit 1)
        )
      )
    )
  )

  (symbol (lib_id "sdi-mipi-bridge:GNDREF") (at 372.11 254 0) (unit 1)
    (in_bom yes) (on_board yes) (dnp no)
    (property "Reference" "#PWR0106" (at 372.11 260.35 0)
      (effects (font (size 1.27 1.27)) hide)
    )
    (property "Value" "GNDREF" (at 372.237 258.3942 0)
      (effects (font (size 1.27 1.27)))
    )
    (property "Footprint" "" (at 372.11 254 0)
      (effects (font (size 1.27 1.27)) hide)
    )
    (property "Datasheet" "" (at 372.11 254 0)
      (effects (font (size 1.27 1.27)) hide)
    )
    (pin "1")
    (instances
      (project "sdi-mipi-bridge"
        (path ""
          (reference "#PWR0106") (unit 1)
        )
      )
    )
  )

  (symbol (lib_id "sdi-mipi-bridge:C_10n_0402") (at 156.21 144.78 0) (unit 1)
    (in_bom yes) (on_board yes) (dnp no)
    (property "Reference" "C36" (at 158.75 142.24 0)
      (effects (font (size 1.27 1.27)))
    )
    (property "Value" "C_10n_0402" (at 176.53 154.94 0)
      (effects (font (size 1.27 1.27) (thickness 0.15)) (justify left bottom) hide)
    )
    (property "Footprint" "sdi-mipi-bridge-footprints:C_0402_1005Metric" (at 176.53 157.48 0)
      (effects (font (size 1.27 1.27) (thickness 0.15)) (justify left bottom) hide)
    )
    (property "Datasheet" "https://search.murata.co.jp/Ceramy/image/img/A01X/G101/ENG/GRM155R71H103KA88-01.pdf" (at 176.53 160.02 0)
      (effects (font (size 1.27 1.27) (thickness 0.15)) (justify left bottom) hide)
    )
    (property "Manufacturer" "Murata" (at 176.53 165.1 0)
      (effects (font (size 1.27 1.27) (thickness 0.15)) (justify left bottom) hide)
    )
    (property "MPN" "GRM155R71H103KA88D" (at 176.53 162.56 0)
      (effects (font (size 1.27 1.27) (thickness 0.15)) (justify left bottom) hide)
    )
    (property "Val" "10n" (at 158.75 147.32 0)
      (effects (font (size 1.27 1.27) (thickness 0.15)))
    )
    (property "License" "Apache-2.0" (at 176.53 167.64 0)
      (effects (font (size 1.27 1.27) (thickness 0.15)) (justify left bottom) hide)
    )
    (property "Author" "Antmicro" (at 176.53 170.18 0)
      (effects (font (size 1.27 1.27) (thickness 0.15)) (justify left bottom) hide)
    )
    (property "Voltage" "50V" (at 176.53 172.72 0)
      (effects (font (size 1.27 1.27)) (justify left bottom) hide)
    )
    (property "Dielectric" "X7R" (at 176.53 175.26 0)
      (effects (font (size 1.27 1.27)) (justify left bottom) hide)
    )
    (pin "1")
    (pin "2")
    (instances
      (project "sdi-mipi-bridge"
        (path ""
          (reference "C36") (unit 1)
        )
      )
    )
  )

  (symbol (lib_id "sdi-mipi-bridge:GNDA") (at 184.15 138.43 0) (mirror y) (unit 1)
    (in_bom yes) (on_board yes) (dnp no)
    (property "Reference" "#PWR035" (at 184.15 144.78 0)
      (effects (font (size 1.27 1.27)) hide)
    )
    (property "Value" "GNDA" (at 184.023 142.8242 0)
      (effects (font (size 1.27 1.27)))
    )
    (property "Footprint" "" (at 184.15 138.43 0)
      (effects (font (size 1.27 1.27)) hide)
    )
    (property "Datasheet" "" (at 184.15 138.43 0)
      (effects (font (size 1.27 1.27)) hide)
    )
    (pin "1")
    (instances
      (project "sdi-mipi-bridge"
        (path ""
          (reference "#PWR035") (unit 1)
        )
      )
    )
  )

  (symbol (lib_id "sdi-mipi-bridge:GNDREF") (at 372.11 238.76 0) (unit 1)
    (in_bom yes) (on_board yes) (dnp no)
    (property "Reference" "#PWR0113" (at 372.11 245.11 0)
      (effects (font (size 1.27 1.27)) hide)
    )
    (property "Value" "GNDREF" (at 372.237 243.1542 0)
      (effects (font (size 1.27 1.27)))
    )
    (property "Footprint" "" (at 372.11 238.76 0)
      (effects (font (size 1.27 1.27)) hide)
    )
    (property "Datasheet" "" (at 372.11 238.76 0)
      (effects (font (size 1.27 1.27)) hide)
    )
    (pin "1")
    (instances
      (project "sdi-mipi-bridge"
        (path ""
          (reference "#PWR0113") (unit 1)
        )
      )
    )
  )

  (symbol (lib_id "sdi-mipi-bridge:R_75R_0603") (at 147.32 144.78 0) (mirror x) (unit 1)
    (in_bom yes) (on_board yes) (dnp no)
    (property "Reference" "R18" (at 149.86 142.24 0)
      (effects (font (size 1.27 1.27)))
    )
    (property "Value" "R_75R_0603" (at 167.64 132.08 0)
      (effects (font (size 1.27 1.27) (thickness 0.15)) (justify left bottom) hide)
    )
    (property "Footprint" "sdi-mipi-bridge-footprints:R_0603_1608Metric" (at 167.64 129.54 0)
      (effects (font (size 1.27 1.27) (thickness 0.15)) (justify left bottom) hide)
    )
    (property "Datasheet" "https://www.bourns.com/docs/product-datasheets/cr.pdf" (at 167.64 127 0)
      (effects (font (size 1.27 1.27) (thickness 0.15)) (justify left bottom) hide)
    )
    (property "Manufacturer" "Bourns" (at 167.64 121.92 0)
      (effects (font (size 1.27 1.27) (thickness 0.15)) (justify left bottom) hide)
    )
    (property "MPN" "CR0603-FX-75R0ELF" (at 167.64 124.46 0)
      (effects (font (size 1.27 1.27) (thickness 0.15)) (justify left bottom) hide)
    )
    (property "Val" "75R" (at 149.86 147.32 0)
      (effects (font (size 1.27 1.27) (thickness 0.15)))
    )
    (property "License" "Apache-2.0" (at 167.64 119.38 0)
      (effects (font (size 1.27 1.27) (thickness 0.15)) (justify left bottom) hide)
    )
    (property "Author" "Antmicro" (at 167.64 116.84 0)
      (effects (font (size 1.27 1.27) (thickness 0.15)) (justify left bottom) hide)
    )
    (property "Tolerance" "1%" (at 167.64 134.62 0)
      (effects (font (size 1.27 1.27)) (justify left bottom) hide)
    )
    (pin "1")
    (pin "2")
    (instances
      (project "sdi-mipi-bridge"
        (path ""
          (reference "R18") (unit 1)
        )
      )
    )
  )

  (symbol (lib_id "sdi-mipi-bridge:GNDREF") (at 372.11 224.79 0) (unit 1)
    (in_bom yes) (on_board yes) (dnp no)
    (property "Reference" "#PWR0116" (at 372.11 231.14 0)
      (effects (font (size 1.27 1.27)) hide)
    )
    (property "Value" "GNDREF" (at 372.237 229.1842 0)
      (effects (font (size 1.27 1.27)))
    )
    (property "Footprint" "" (at 372.11 224.79 0)
      (effects (font (size 1.27 1.27)) hide)
    )
    (property "Datasheet" "" (at 372.11 224.79 0)
      (effects (font (size 1.27 1.27)) hide)
    )
    (pin "1")
    (instances
      (project "sdi-mipi-bridge"
        (path ""
          (reference "#PWR0116") (unit 1)
        )
      )
    )
  )

  (symbol (lib_id "sdi-mipi-bridge:R_0R_0402") (at 101.6 158.75 0) (unit 1)
    (in_bom yes) (on_board yes) (dnp no)
    (property "Reference" "R71" (at 104.14 156.21 0)
      (effects (font (size 1.27 1.27)))
    )
    (property "Value" "R_0R_0402" (at 121.92 171.45 0)
      (effects (font (size 1.27 1.27) (thickness 0.15)) (justify left bottom) hide)
    )
    (property "Footprint" "sdi-mipi-bridge-footprints:R_0402_1005Metric" (at 121.92 173.99 0)
      (effects (font (size 1.27 1.27) (thickness 0.15)) (justify left bottom) hide)
    )
    (property "Datasheet" "https://industrial.panasonic.com/cdbs/www-data/pdf/RDA0000/AOA0000C301.pdf" (at 121.92 176.53 0)
      (effects (font (size 1.27 1.27) (thickness 0.15)) (justify left bottom) hide)
    )
    (property "Manufacturer" "Panasonic" (at 121.92 181.61 0)
      (effects (font (size 1.27 1.27) (thickness 0.15)) (justify left bottom) hide)
    )
    (property "MPN" "ERJ2GE0R00X" (at 121.92 179.07 0)
      (effects (font (size 1.27 1.27) (thickness 0.15)) (justify left bottom) hide)
    )
    (property "Val" "0R" (at 104.14 161.29 0)
      (effects (font (size 1.27 1.27) (thickness 0.15)))
    )
    (property "License" "Apache-2.0" (at 121.92 184.15 0)
      (effects (font (size 1.27 1.27) (thickness 0.15)) (justify left bottom) hide)
    )
    (property "Author" "Antmicro" (at 121.92 186.69 0)
      (effects (font (size 1.27 1.27) (thickness 0.15)) (justify left bottom) hide)
    )
    (property "Tolerance" "~" (at 121.92 168.91 0)
      (effects (font (size 1.27 1.27)) (justify left bottom) hide)
    )
    (property "Current" "1A" (at 121.92 189.23 0)
      (effects (font (size 1.27 1.27) (thickness 0.15)) (justify left bottom) hide)
    )
    (pin "1")
    (pin "2")
    (instances
      (project "sdi-mipi-bridge"
        (path ""
          (reference "R71") (unit 1)
        )
      )
    )
  )

  (symbol (lib_id "sdi-mipi-bridge:GNDREF") (at 372.11 205.74 0) (unit 1)
    (in_bom yes) (on_board yes) (dnp no)
    (property "Reference" "#PWR0119" (at 372.11 212.09 0)
      (effects (font (size 1.27 1.27)) hide)
    )
    (property "Value" "GNDREF" (at 372.237 210.1342 0)
      (effects (font (size 1.27 1.27)))
    )
    (property "Footprint" "" (at 372.11 205.74 0)
      (effects (font (size 1.27 1.27)) hide)
    )
    (property "Datasheet" "" (at 372.11 205.74 0)
      (effects (font (size 1.27 1.27)) hide)
    )
    (pin "1")
    (instances
      (project "sdi-mipi-bridge"
        (path ""
          (reference "#PWR0119") (unit 1)
        )
      )
    )
  )

  (symbol (lib_id "sdi-mipi-bridge:C_4u7_0402") (at 177.8 160.02 0) (unit 1)
    (in_bom yes) (on_board yes) (dnp no)
    (property "Reference" "C31" (at 180.34 154.94 0)
      (effects (font (size 1.27 1.27)))
    )
    (property "Value" "C_4u7_0402" (at 198.12 170.18 0)
      (effects (font (size 1.27 1.27) (thickness 0.15)) (justify left bottom) hide)
    )
    (property "Footprint" "sdi-mipi-bridge-footprints:C_0402_1005Metric" (at 198.12 172.72 0)
      (effects (font (size 1.27 1.27) (thickness 0.15)) (justify left bottom) hide)
    )
    (property "Datasheet" " " (at 198.12 175.26 0)
      (effects (font (size 1.27 1.27) (thickness 0.15)) (justify left bottom) hide)
    )
    (property "Manufacturer" "Murata" (at 198.12 180.34 0)
      (effects (font (size 1.27 1.27) (thickness 0.15)) (justify left bottom) hide)
    )
    (property "MPN" "GRM155R61A475MEAAD" (at 198.12 177.8 0)
      (effects (font (size 1.27 1.27) (thickness 0.15)) (justify left bottom) hide)
    )
    (property "Val" "4u7" (at 180.34 157.48 0)
      (effects (font (size 1.27 1.27) (thickness 0.15)))
    )
    (property "License" "Apache-2.0" (at 198.12 182.88 0)
      (effects (font (size 1.27 1.27) (thickness 0.15)) (justify left bottom) hide)
    )
    (property "Author" "Antmicro" (at 198.12 185.42 0)
      (effects (font (size 1.27 1.27) (thickness 0.15)) (justify left bottom) hide)
    )
    (property "Voltage" "" (at 198.12 187.96 0)
      (effects (font (size 1.27 1.27)) (justify left bottom) hide)
    )
    (property "Dielectric" "" (at 198.12 190.5 0)
      (effects (font (size 1.27 1.27)) (justify left bottom) hide)
    )
    (pin "1")
    (pin "2")
    (instances
      (project "sdi-mipi-bridge"
        (path ""
          (reference "C31") (unit 1)
        )
      )
    )
  )

  (symbol (lib_id "sdi-mipi-bridge:R_2k2_0402") (at 524.51 156.21 270) (unit 1)
    (in_bom yes) (on_board yes) (dnp no)
    (property "Reference" "R85" (at 525.78 157.48 90)
      (effects (font (size 1.27 1.27)) (justify left))
    )
    (property "Value" "R_2k2_0402" (at 511.81 176.53 0)
      (effects (font (size 1.27 1.27) (thickness 0.15)) (justify left bottom) hide)
    )
    (property "Footprint" "sdi-mipi-bridge-footprints:R_0402_1005Metric" (at 509.27 176.53 0)
      (effects (font (size 1.27 1.27) (thickness 0.15)) (justify left bottom) hide)
    )
    (property "Datasheet" "https://www.bourns.com/docs/product-datasheets/cr.pdf" (at 506.73 176.53 0)
      (effects (font (size 1.27 1.27) (thickness 0.15)) (justify left bottom) hide)
    )
    (property "Manufacturer" "Bourns" (at 501.65 176.53 0)
      (effects (font (size 1.27 1.27) (thickness 0.15)) (justify left bottom) hide)
    )
    (property "MPN" "CR0402-FX-2201GLF" (at 504.19 176.53 0)
      (effects (font (size 1.27 1.27) (thickness 0.15)) (justify left bottom) hide)
    )
    (property "Val" "2k2" (at 525.78 160.02 90)
      (effects (font (size 1.27 1.27) (thickness 0.15)) (justify left))
    )
    (property "License" "Apache-2.0" (at 499.11 176.53 0)
      (effects (font (size 1.27 1.27) (thickness 0.15)) (justify left bottom) hide)
    )
    (property "Author" "Antmicro" (at 496.57 176.53 0)
      (effects (font (size 1.27 1.27) (thickness 0.15)) (justify left bottom) hide)
    )
    (property "Tolerance" "1%" (at 514.35 176.53 0)
      (effects (font (size 1.27 1.27)) (justify left bottom) hide)
    )
    (property "DNP" "DNP" (at 524.51 156.21 0)
      (effects (font (size 1.27 1.27)) hide)
    )
    (pin "1")
    (pin "2")
    (instances
      (project "sdi-mipi-bridge"
        (path ""
          (reference "R85") (unit 1)
        )
      )
    )
  )

  (symbol (lib_id "sdi-mipi-bridge:R_75R_0603") (at 182.88 137.16 180) (unit 1)
    (in_bom yes) (on_board yes) (dnp no)
    (property "Reference" "R20" (at 180.34 134.62 0)
      (effects (font (size 1.27 1.27)))
    )
    (property "Value" "R_75R_0603" (at 162.56 124.46 0)
      (effects (font (size 1.27 1.27) (thickness 0.15)) (justify left bottom) hide)
    )
    (property "Footprint" "sdi-mipi-bridge-footprints:R_0603_1608Metric" (at 162.56 121.92 0)
      (effects (font (size 1.27 1.27) (thickness 0.15)) (justify left bottom) hide)
    )
    (property "Datasheet" "https://www.bourns.com/docs/product-datasheets/cr.pdf" (at 162.56 119.38 0)
      (effects (font (size 1.27 1.27) (thickness 0.15)) (justify left bottom) hide)
    )
    (property "Manufacturer" "Bourns" (at 162.56 114.3 0)
      (effects (font (size 1.27 1.27) (thickness 0.15)) (justify left bottom) hide)
    )
    (property "MPN" "CR0603-FX-75R0ELF" (at 162.56 116.84 0)
      (effects (font (size 1.27 1.27) (thickness 0.15)) (justify left bottom) hide)
    )
    (property "Val" "75R" (at 180.34 139.7 0)
      (effects (font (size 1.27 1.27) (thickness 0.15)))
    )
    (property "License" "Apache-2.0" (at 162.56 111.76 0)
      (effects (font (size 1.27 1.27) (thickness 0.15)) (justify left bottom) hide)
    )
    (property "Author" "Antmicro" (at 162.56 109.22 0)
      (effects (font (size 1.27 1.27) (thickness 0.15)) (justify left bottom) hide)
    )
    (property "Tolerance" "1%" (at 162.56 127 0)
      (effects (font (size 1.27 1.27)) (justify left bottom) hide)
    )
    (pin "1")
    (pin "2")
    (instances
      (project "sdi-mipi-bridge"
        (path ""
          (reference "R20") (unit 1)
        )
      )
    )
  )

  (symbol (lib_id "sdi-mipi-bridge:C_4u7_0402") (at 175.26 137.16 180) (unit 1)
    (in_bom yes) (on_board yes) (dnp no)
    (property "Reference" "C23" (at 172.72 134.62 0)
      (effects (font (size 1.27 1.27)))
    )
    (property "Value" "C_4u7_0402" (at 154.94 127 0)
      (effects (font (size 1.27 1.27) (thickness 0.15)) (justify left bottom) hide)
    )
    (property "Footprint" "sdi-mipi-bridge-footprints:C_0402_1005Metric" (at 154.94 124.46 0)
      (effects (font (size 1.27 1.27) (thickness 0.15)) (justify left bottom) hide)
    )
    (property "Datasheet" " " (at 154.94 121.92 0)
      (effects (font (size 1.27 1.27) (thickness 0.15)) (justify left bottom) hide)
    )
    (property "Manufacturer" "Murata" (at 154.94 116.84 0)
      (effects (font (size 1.27 1.27) (thickness 0.15)) (justify left bottom) hide)
    )
    (property "MPN" "GRM155R61A475MEAAD" (at 154.94 119.38 0)
      (effects (font (size 1.27 1.27) (thickness 0.15)) (justify left bottom) hide)
    )
    (property "Val" "4u7" (at 172.72 139.7 0)
      (effects (font (size 1.27 1.27) (thickness 0.15)))
    )
    (property "License" "Apache-2.0" (at 154.94 114.3 0)
      (effects (font (size 1.27 1.27) (thickness 0.15)) (justify left bottom) hide)
    )
    (property "Author" "Antmicro" (at 154.94 111.76 0)
      (effects (font (size 1.27 1.27) (thickness 0.15)) (justify left bottom) hide)
    )
    (property "Voltage" "" (at 154.94 109.22 0)
      (effects (font (size 1.27 1.27)) (justify left bottom) hide)
    )
    (property "Dielectric" "" (at 154.94 106.68 0)
      (effects (font (size 1.27 1.27)) (justify left bottom) hide)
    )
    (pin "1")
    (pin "2")
    (instances
      (project "sdi-mipi-bridge"
        (path ""
          (reference "C23") (unit 1)
        )
      )
    )
  )

  (symbol (lib_id "sdi-mipi-bridge:+1V2") (at 34.29 300.99 0) (unit 1)
    (in_bom yes) (on_board yes) (dnp no)
    (property "Reference" "#PWR03" (at 34.29 304.8 0)
      (effects (font (size 1.27 1.27)) hide)
    )
    (property "Value" "+1V2" (at 34.671 296.5958 0)
      (effects (font (size 1.27 1.27)))
    )
    (property "Footprint" "" (at 34.29 300.99 0)
      (effects (font (size 1.27 1.27)) hide)
    )
    (property "Datasheet" "" (at 34.29 300.99 0)
      (effects (font (size 1.27 1.27)) hide)
    )
    (pin "1")
    (instances
      (project "sdi-mipi-bridge"
        (path ""
          (reference "#PWR03") (unit 1)
        )
      )
    )
  )

  (symbol (lib_id "sdi-mipi-bridge:+1V2") (at 144.78 262.89 0) (unit 1)
    (in_bom yes) (on_board yes) (dnp no)
    (property "Reference" "#PWR020" (at 144.78 266.7 0)
      (effects (font (size 1.27 1.27)) hide)
    )
    (property "Value" "+1V2" (at 145.161 258.4958 0)
      (effects (font (size 1.27 1.27)))
    )
    (property "Footprint" "" (at 144.78 262.89 0)
      (effects (font (size 1.27 1.27)) hide)
    )
    (property "Datasheet" "" (at 144.78 262.89 0)
      (effects (font (size 1.27 1.27)) hide)
    )
    (pin "1")
    (instances
      (project "sdi-mipi-bridge"
        (path ""
          (reference "#PWR020") (unit 1)
        )
      )
    )
  )

  (symbol (lib_id "sdi-mipi-bridge:+3.3VA") (at 177.8 222.25 0) (unit 1)
    (in_bom yes) (on_board yes) (dnp no)
    (property "Reference" "#PWR025" (at 177.8 226.06 0)
      (effects (font (size 1.27 1.27)) hide)
    )
    (property "Value" "+3.3VA" (at 178.181 217.8558 0)
      (effects (font (size 1.27 1.27)))
    )
    (property "Footprint" "" (at 177.8 222.25 0)
      (effects (font (size 1.27 1.27)) hide)
    )
    (property "Datasheet" "" (at 177.8 222.25 0)
      (effects (font (size 1.27 1.27)) hide)
    )
    (pin "1")
    (instances
      (project "sdi-mipi-bridge"
        (path ""
          (reference "#PWR025") (unit 1)
        )
      )
    )
  )

  (symbol (lib_id "sdi-mipi-bridge:GNDREF") (at 34.29 309.88 0) (unit 1)
    (in_bom yes) (on_board yes) (dnp no)
    (property "Reference" "#PWR04" (at 34.29 316.23 0)
      (effects (font (size 1.27 1.27)) hide)
    )
    (property "Value" "GNDREF" (at 34.417 314.2742 0)
      (effects (font (size 1.27 1.27)))
    )
    (property "Footprint" "" (at 34.29 309.88 0)
      (effects (font (size 1.27 1.27)) hide)
    )
    (property "Datasheet" "" (at 34.29 309.88 0)
      (effects (font (size 1.27 1.27)) hide)
    )
    (pin "1")
    (instances
      (project "sdi-mipi-bridge"
        (path ""
          (reference "#PWR04") (unit 1)
        )
      )
    )
  )

  (symbol (lib_id "sdi-mipi-bridge:C_10n_0402") (at 34.29 309.88 90) (unit 1)
    (in_bom yes) (on_board yes) (dnp no)
    (property "Reference" "C2" (at 36.83 306.07 90)
      (effects (font (size 1.27 1.27)) (justify right))
    )
    (property "Value" "C_10n_0402" (at 44.45 289.56 0)
      (effects (font (size 1.27 1.27) (thickness 0.15)) (justify left bottom) hide)
    )
    (property "Footprint" "sdi-mipi-bridge-footprints:C_0402_1005Metric" (at 46.99 289.56 0)
      (effects (font (size 1.27 1.27) (thickness 0.15)) (justify left bottom) hide)
    )
    (property "Datasheet" "https://search.murata.co.jp/Ceramy/image/img/A01X/G101/ENG/GRM155R71H103KA88-01.pdf" (at 49.53 289.56 0)
      (effects (font (size 1.27 1.27) (thickness 0.15)) (justify left bottom) hide)
    )
    (property "Manufacturer" "Murata" (at 54.61 289.56 0)
      (effects (font (size 1.27 1.27) (thickness 0.15)) (justify left bottom) hide)
    )
    (property "MPN" "GRM155R71H103KA88D" (at 52.07 289.56 0)
      (effects (font (size 1.27 1.27) (thickness 0.15)) (justify left bottom) hide)
    )
    (property "Val" "10n" (at 36.83 308.61 90)
      (effects (font (size 1.27 1.27) (thickness 0.15)) (justify right))
    )
    (property "License" "Apache-2.0" (at 57.15 289.56 0)
      (effects (font (size 1.27 1.27) (thickness 0.15)) (justify left bottom) hide)
    )
    (property "Author" "Antmicro" (at 59.69 289.56 0)
      (effects (font (size 1.27 1.27) (thickness 0.15)) (justify left bottom) hide)
    )
    (property "Voltage" "50V" (at 62.23 289.56 0)
      (effects (font (size 1.27 1.27)) (justify left bottom) hide)
    )
    (property "Dielectric" "X7R" (at 64.77 289.56 0)
      (effects (font (size 1.27 1.27)) (justify left bottom) hide)
    )
    (pin "1")
    (pin "2")
    (instances
      (project "sdi-mipi-bridge"
        (path ""
          (reference "C2") (unit 1)
        )
      )
    )
  )

  (symbol (lib_id "sdi-mipi-bridge:C_10n_0402") (at 41.91 309.88 90) (unit 1)
    (in_bom yes) (on_board yes) (dnp no) (fields_autoplaced)
    (property "Reference" "C4" (at 44.45 306.0635 90)
      (effects (font (size 1.27 1.27)) (justify right))
    )
    (property "Value" "C_10n_0402" (at 52.07 289.56 0)
      (effects (font (size 1.27 1.27) (thickness 0.15)) (justify left bottom) hide)
    )
    (property "Footprint" "sdi-mipi-bridge-footprints:C_0402_1005Metric" (at 54.61 289.56 0)
      (effects (font (size 1.27 1.27) (thickness 0.15)) (justify left bottom) hide)
    )
    (property "Datasheet" "https://search.murata.co.jp/Ceramy/image/img/A01X/G101/ENG/GRM155R71H103KA88-01.pdf" (at 57.15 289.56 0)
      (effects (font (size 1.27 1.27) (thickness 0.15)) (justify left bottom) hide)
    )
    (property "Manufacturer" "Murata" (at 62.23 289.56 0)
      (effects (font (size 1.27 1.27) (thickness 0.15)) (justify left bottom) hide)
    )
    (property "MPN" "GRM155R71H103KA88D" (at 59.69 289.56 0)
      (effects (font (size 1.27 1.27) (thickness 0.15)) (justify left bottom) hide)
    )
    (property "Val" "10n" (at 44.45 308.6035 90)
      (effects (font (size 1.27 1.27) (thickness 0.15)) (justify right))
    )
    (property "License" "Apache-2.0" (at 64.77 289.56 0)
      (effects (font (size 1.27 1.27) (thickness 0.15)) (justify left bottom) hide)
    )
    (property "Author" "Antmicro" (at 67.31 289.56 0)
      (effects (font (size 1.27 1.27) (thickness 0.15)) (justify left bottom) hide)
    )
    (property "Voltage" "50V" (at 69.85 289.56 0)
      (effects (font (size 1.27 1.27)) (justify left bottom) hide)
    )
    (property "Dielectric" "X7R" (at 72.39 289.56 0)
      (effects (font (size 1.27 1.27)) (justify left bottom) hide)
    )
    (pin "1")
    (pin "2")
    (instances
      (project "sdi-mipi-bridge"
        (path ""
          (reference "C4") (unit 1)
        )
      )
    )
  )

  (symbol (lib_id "sdi-mipi-bridge:C_10n_0402") (at 49.53 309.88 90) (unit 1)
    (in_bom yes) (on_board yes) (dnp no)
    (property "Reference" "C6" (at 52.07 306.0635 90)
      (effects (font (size 1.27 1.27)) (justify right))
    )
    (property "Value" "C_10n_0402" (at 59.69 289.56 0)
      (effects (font (size 1.27 1.27) (thickness 0.15)) (justify left bottom) hide)
    )
    (property "Footprint" "sdi-mipi-bridge-footprints:C_0402_1005Metric" (at 62.23 289.56 0)
      (effects (font (size 1.27 1.27) (thickness 0.15)) (justify left bottom) hide)
    )
    (property "Datasheet" "https://search.murata.co.jp/Ceramy/image/img/A01X/G101/ENG/GRM155R71H103KA88-01.pdf" (at 64.77 289.56 0)
      (effects (font (size 1.27 1.27) (thickness 0.15)) (justify left bottom) hide)
    )
    (property "Manufacturer" "Murata" (at 69.85 289.56 0)
      (effects (font (size 1.27 1.27) (thickness 0.15)) (justify left bottom) hide)
    )
    (property "MPN" "GRM155R71H103KA88D" (at 67.31 289.56 0)
      (effects (font (size 1.27 1.27) (thickness 0.15)) (justify left bottom) hide)
    )
    (property "Val" "10n" (at 52.07 308.6035 90)
      (effects (font (size 1.27 1.27) (thickness 0.15)) (justify right))
    )
    (property "License" "Apache-2.0" (at 72.39 289.56 0)
      (effects (font (size 1.27 1.27) (thickness 0.15)) (justify left bottom) hide)
    )
    (property "Author" "Antmicro" (at 74.93 289.56 0)
      (effects (font (size 1.27 1.27) (thickness 0.15)) (justify left bottom) hide)
    )
    (property "Voltage" "50V" (at 77.47 289.56 0)
      (effects (font (size 1.27 1.27)) (justify left bottom) hide)
    )
    (property "Dielectric" "X7R" (at 80.01 289.56 0)
      (effects (font (size 1.27 1.27)) (justify left bottom) hide)
    )
    (pin "1")
    (pin "2")
    (instances
      (project "sdi-mipi-bridge"
        (path ""
          (reference "C6") (unit 1)
        )
      )
    )
  )

  (symbol (lib_id "sdi-mipi-bridge:C_10n_0402") (at 57.15 309.88 90) (unit 1)
    (in_bom yes) (on_board yes) (dnp no) (fields_autoplaced)
    (property "Reference" "C8" (at 59.69 306.0635 90)
      (effects (font (size 1.27 1.27)) (justify right))
    )
    (property "Value" "C_10n_0402" (at 67.31 289.56 0)
      (effects (font (size 1.27 1.27) (thickness 0.15)) (justify left bottom) hide)
    )
    (property "Footprint" "sdi-mipi-bridge-footprints:C_0402_1005Metric" (at 69.85 289.56 0)
      (effects (font (size 1.27 1.27) (thickness 0.15)) (justify left bottom) hide)
    )
    (property "Datasheet" "https://search.murata.co.jp/Ceramy/image/img/A01X/G101/ENG/GRM155R71H103KA88-01.pdf" (at 72.39 289.56 0)
      (effects (font (size 1.27 1.27) (thickness 0.15)) (justify left bottom) hide)
    )
    (property "Manufacturer" "Murata" (at 77.47 289.56 0)
      (effects (font (size 1.27 1.27) (thickness 0.15)) (justify left bottom) hide)
    )
    (property "MPN" "GRM155R71H103KA88D" (at 74.93 289.56 0)
      (effects (font (size 1.27 1.27) (thickness 0.15)) (justify left bottom) hide)
    )
    (property "Val" "10n" (at 59.69 308.6035 90)
      (effects (font (size 1.27 1.27) (thickness 0.15)) (justify right))
    )
    (property "License" "Apache-2.0" (at 80.01 289.56 0)
      (effects (font (size 1.27 1.27) (thickness 0.15)) (justify left bottom) hide)
    )
    (property "Author" "Antmicro" (at 82.55 289.56 0)
      (effects (font (size 1.27 1.27) (thickness 0.15)) (justify left bottom) hide)
    )
    (property "Voltage" "50V" (at 85.09 289.56 0)
      (effects (font (size 1.27 1.27)) (justify left bottom) hide)
    )
    (property "Dielectric" "X7R" (at 87.63 289.56 0)
      (effects (font (size 1.27 1.27)) (justify left bottom) hide)
    )
    (pin "1")
    (pin "2")
    (instances
      (project "sdi-mipi-bridge"
        (path ""
          (reference "C8") (unit 1)
        )
      )
    )
  )

  (symbol (lib_id "sdi-mipi-bridge:C_10n_0402") (at 76.2 309.88 90) (unit 1)
    (in_bom yes) (on_board yes) (dnp no)
    (property "Reference" "C11" (at 77.47 306.07 90)
      (effects (font (size 1.27 1.27)) (justify right))
    )
    (property "Value" "C_10n_0402" (at 86.36 289.56 0)
      (effects (font (size 1.27 1.27) (thickness 0.15)) (justify left bottom) hide)
    )
    (property "Footprint" "sdi-mipi-bridge-footprints:C_0402_1005Metric" (at 88.9 289.56 0)
      (effects (font (size 1.27 1.27) (thickness 0.15)) (justify left bottom) hide)
    )
    (property "Datasheet" "https://search.murata.co.jp/Ceramy/image/img/A01X/G101/ENG/GRM155R71H103KA88-01.pdf" (at 91.44 289.56 0)
      (effects (font (size 1.27 1.27) (thickness 0.15)) (justify left bottom) hide)
    )
    (property "Manufacturer" "Murata" (at 96.52 289.56 0)
      (effects (font (size 1.27 1.27) (thickness 0.15)) (justify left bottom) hide)
    )
    (property "MPN" "GRM155R71H103KA88D" (at 93.98 289.56 0)
      (effects (font (size 1.27 1.27) (thickness 0.15)) (justify left bottom) hide)
    )
    (property "Val" "10n" (at 77.47 308.61 90)
      (effects (font (size 1.27 1.27) (thickness 0.15)) (justify right))
    )
    (property "License" "Apache-2.0" (at 99.06 289.56 0)
      (effects (font (size 1.27 1.27) (thickness 0.15)) (justify left bottom) hide)
    )
    (property "Author" "Antmicro" (at 101.6 289.56 0)
      (effects (font (size 1.27 1.27) (thickness 0.15)) (justify left bottom) hide)
    )
    (property "Voltage" "50V" (at 104.14 289.56 0)
      (effects (font (size 1.27 1.27)) (justify left bottom) hide)
    )
    (property "Dielectric" "X7R" (at 106.68 289.56 0)
      (effects (font (size 1.27 1.27)) (justify left bottom) hide)
    )
    (pin "1")
    (pin "2")
    (instances
      (project "sdi-mipi-bridge"
        (path ""
          (reference "C11") (unit 1)
        )
      )
    )
  )

  (symbol (lib_id "sdi-mipi-bridge:C_10n_0402") (at 83.82 309.88 90) (unit 1)
    (in_bom yes) (on_board yes) (dnp no)
    (property "Reference" "C13" (at 85.09 306.07 90)
      (effects (font (size 1.27 1.27)) (justify right))
    )
    (property "Value" "C_10n_0402" (at 93.98 289.56 0)
      (effects (font (size 1.27 1.27) (thickness 0.15)) (justify left bottom) hide)
    )
    (property "Footprint" "sdi-mipi-bridge-footprints:C_0402_1005Metric" (at 96.52 289.56 0)
      (effects (font (size 1.27 1.27) (thickness 0.15)) (justify left bottom) hide)
    )
    (property "Datasheet" "https://search.murata.co.jp/Ceramy/image/img/A01X/G101/ENG/GRM155R71H103KA88-01.pdf" (at 99.06 289.56 0)
      (effects (font (size 1.27 1.27) (thickness 0.15)) (justify left bottom) hide)
    )
    (property "Manufacturer" "Murata" (at 104.14 289.56 0)
      (effects (font (size 1.27 1.27) (thickness 0.15)) (justify left bottom) hide)
    )
    (property "MPN" "GRM155R71H103KA88D" (at 101.6 289.56 0)
      (effects (font (size 1.27 1.27) (thickness 0.15)) (justify left bottom) hide)
    )
    (property "Val" "10n" (at 85.09 308.61 90)
      (effects (font (size 1.27 1.27) (thickness 0.15)) (justify right))
    )
    (property "License" "Apache-2.0" (at 106.68 289.56 0)
      (effects (font (size 1.27 1.27) (thickness 0.15)) (justify left bottom) hide)
    )
    (property "Author" "Antmicro" (at 109.22 289.56 0)
      (effects (font (size 1.27 1.27) (thickness 0.15)) (justify left bottom) hide)
    )
    (property "Voltage" "50V" (at 111.76 289.56 0)
      (effects (font (size 1.27 1.27)) (justify left bottom) hide)
    )
    (property "Dielectric" "X7R" (at 114.3 289.56 0)
      (effects (font (size 1.27 1.27)) (justify left bottom) hide)
    )
    (pin "1")
    (pin "2")
    (instances
      (project "sdi-mipi-bridge"
        (path ""
          (reference "C13") (unit 1)
        )
      )
    )
  )

  (symbol (lib_id "sdi-mipi-bridge:C_10n_0402") (at 91.44 309.88 90) (unit 1)
    (in_bom yes) (on_board yes) (dnp no)
    (property "Reference" "C16" (at 92.71 306.07 90)
      (effects (font (size 1.27 1.27)) (justify right))
    )
    (property "Value" "C_10n_0402" (at 101.6 289.56 0)
      (effects (font (size 1.27 1.27) (thickness 0.15)) (justify left bottom) hide)
    )
    (property "Footprint" "sdi-mipi-bridge-footprints:C_0402_1005Metric" (at 104.14 289.56 0)
      (effects (font (size 1.27 1.27) (thickness 0.15)) (justify left bottom) hide)
    )
    (property "Datasheet" "https://search.murata.co.jp/Ceramy/image/img/A01X/G101/ENG/GRM155R71H103KA88-01.pdf" (at 106.68 289.56 0)
      (effects (font (size 1.27 1.27) (thickness 0.15)) (justify left bottom) hide)
    )
    (property "Manufacturer" "Murata" (at 111.76 289.56 0)
      (effects (font (size 1.27 1.27) (thickness 0.15)) (justify left bottom) hide)
    )
    (property "MPN" "GRM155R71H103KA88D" (at 109.22 289.56 0)
      (effects (font (size 1.27 1.27) (thickness 0.15)) (justify left bottom) hide)
    )
    (property "Val" "10n" (at 92.71 308.61 90)
      (effects (font (size 1.27 1.27) (thickness 0.15)) (justify right))
    )
    (property "License" "Apache-2.0" (at 114.3 289.56 0)
      (effects (font (size 1.27 1.27) (thickness 0.15)) (justify left bottom) hide)
    )
    (property "Author" "Antmicro" (at 116.84 289.56 0)
      (effects (font (size 1.27 1.27) (thickness 0.15)) (justify left bottom) hide)
    )
    (property "Voltage" "50V" (at 119.38 289.56 0)
      (effects (font (size 1.27 1.27)) (justify left bottom) hide)
    )
    (property "Dielectric" "X7R" (at 121.92 289.56 0)
      (effects (font (size 1.27 1.27)) (justify left bottom) hide)
    )
    (pin "1")
    (pin "2")
    (instances
      (project "sdi-mipi-bridge"
        (path ""
          (reference "C16") (unit 1)
        )
      )
    )
  )

  (symbol (lib_id "sdi-mipi-bridge:GNDA") (at 76.2 309.88 0) (unit 1)
    (in_bom yes) (on_board yes) (dnp no)
    (property "Reference" "#PWR010" (at 76.2 316.23 0)
      (effects (font (size 1.27 1.27)) hide)
    )
    (property "Value" "GNDA" (at 76.327 314.2742 0)
      (effects (font (size 1.27 1.27)))
    )
    (property "Footprint" "" (at 76.2 309.88 0)
      (effects (font (size 1.27 1.27)) hide)
    )
    (property "Datasheet" "" (at 76.2 309.88 0)
      (effects (font (size 1.27 1.27)) hide)
    )
    (pin "1")
    (instances
      (project "sdi-mipi-bridge"
        (path ""
          (reference "#PWR010") (unit 1)
        )
      )
    )
  )

  (symbol (lib_id "sdi-mipi-bridge:C_10n_0402") (at 177.8 232.41 90) (unit 1)
    (in_bom yes) (on_board yes) (dnp no) (fields_autoplaced)
    (property "Reference" "C32" (at 180.34 228.5935 90)
      (effects (font (size 1.27 1.27)) (justify right))
    )
    (property "Value" "C_10n_0402" (at 187.96 212.09 0)
      (effects (font (size 1.27 1.27) (thickness 0.15)) (justify left bottom) hide)
    )
    (property "Footprint" "sdi-mipi-bridge-footprints:C_0402_1005Metric" (at 190.5 212.09 0)
      (effects (font (size 1.27 1.27) (thickness 0.15)) (justify left bottom) hide)
    )
    (property "Datasheet" "https://search.murata.co.jp/Ceramy/image/img/A01X/G101/ENG/GRM155R71H103KA88-01.pdf" (at 193.04 212.09 0)
      (effects (font (size 1.27 1.27) (thickness 0.15)) (justify left bottom) hide)
    )
    (property "Manufacturer" "Murata" (at 198.12 212.09 0)
      (effects (font (size 1.27 1.27) (thickness 0.15)) (justify left bottom) hide)
    )
    (property "MPN" "GRM155R71H103KA88D" (at 195.58 212.09 0)
      (effects (font (size 1.27 1.27) (thickness 0.15)) (justify left bottom) hide)
    )
    (property "Val" "10n" (at 180.34 231.1335 90)
      (effects (font (size 1.27 1.27) (thickness 0.15)) (justify right))
    )
    (property "License" "Apache-2.0" (at 200.66 212.09 0)
      (effects (font (size 1.27 1.27) (thickness 0.15)) (justify left bottom) hide)
    )
    (property "Author" "Antmicro" (at 203.2 212.09 0)
      (effects (font (size 1.27 1.27) (thickness 0.15)) (justify left bottom) hide)
    )
    (property "Voltage" "50V" (at 205.74 212.09 0)
      (effects (font (size 1.27 1.27)) (justify left bottom) hide)
    )
    (property "Dielectric" "X7R" (at 208.28 212.09 0)
      (effects (font (size 1.27 1.27)) (justify left bottom) hide)
    )
    (pin "1")
    (pin "2")
    (instances
      (project "sdi-mipi-bridge"
        (path ""
          (reference "C32") (unit 1)
        )
      )
    )
  )

  (symbol (lib_id "sdi-mipi-bridge:C_10n_0402") (at 144.78 232.41 90) (unit 1)
    (in_bom yes) (on_board yes) (dnp no) (fields_autoplaced)
    (property "Reference" "C19" (at 147.32 228.5935 90)
      (effects (font (size 1.27 1.27)) (justify right))
    )
    (property "Value" "C_10n_0402" (at 154.94 212.09 0)
      (effects (font (size 1.27 1.27) (thickness 0.15)) (justify left bottom) hide)
    )
    (property "Footprint" "sdi-mipi-bridge-footprints:C_0402_1005Metric" (at 157.48 212.09 0)
      (effects (font (size 1.27 1.27) (thickness 0.15)) (justify left bottom) hide)
    )
    (property "Datasheet" "https://search.murata.co.jp/Ceramy/image/img/A01X/G101/ENG/GRM155R71H103KA88-01.pdf" (at 160.02 212.09 0)
      (effects (font (size 1.27 1.27) (thickness 0.15)) (justify left bottom) hide)
    )
    (property "Manufacturer" "Murata" (at 165.1 212.09 0)
      (effects (font (size 1.27 1.27) (thickness 0.15)) (justify left bottom) hide)
    )
    (property "MPN" "GRM155R71H103KA88D" (at 162.56 212.09 0)
      (effects (font (size 1.27 1.27) (thickness 0.15)) (justify left bottom) hide)
    )
    (property "Val" "10n" (at 147.32 231.1335 90)
      (effects (font (size 1.27 1.27) (thickness 0.15)) (justify right))
    )
    (property "License" "Apache-2.0" (at 167.64 212.09 0)
      (effects (font (size 1.27 1.27) (thickness 0.15)) (justify left bottom) hide)
    )
    (property "Author" "Antmicro" (at 170.18 212.09 0)
      (effects (font (size 1.27 1.27) (thickness 0.15)) (justify left bottom) hide)
    )
    (property "Voltage" "50V" (at 172.72 212.09 0)
      (effects (font (size 1.27 1.27)) (justify left bottom) hide)
    )
    (property "Dielectric" "X7R" (at 175.26 212.09 0)
      (effects (font (size 1.27 1.27)) (justify left bottom) hide)
    )
    (pin "1")
    (pin "2")
    (instances
      (project "sdi-mipi-bridge"
        (path ""
          (reference "C19") (unit 1)
        )
      )
    )
  )

  (symbol (lib_id "sdi-mipi-bridge:C_1u_0402") (at 153.67 232.41 90) (unit 1)
    (in_bom yes) (on_board yes) (dnp no) (fields_autoplaced)
    (property "Reference" "C24" (at 156.21 228.5935 90)
      (effects (font (size 1.27 1.27)) (justify right))
    )
    (property "Value" "C_1u_0402" (at 163.83 212.09 0)
      (effects (font (size 1.27 1.27) (thickness 0.15)) (justify left bottom) hide)
    )
    (property "Footprint" "sdi-mipi-bridge-footprints:C_0402_1005Metric" (at 166.37 212.09 0)
      (effects (font (size 1.27 1.27) (thickness 0.15)) (justify left bottom) hide)
    )
    (property "Datasheet" " " (at 168.91 212.09 0)
      (effects (font (size 1.27 1.27) (thickness 0.15)) (justify left bottom) hide)
    )
    (property "Manufacturer" "TDK" (at 173.99 212.09 0)
      (effects (font (size 1.27 1.27) (thickness 0.15)) (justify left bottom) hide)
    )
    (property "MPN" "C1005X6S1A105K050BC" (at 171.45 212.09 0)
      (effects (font (size 1.27 1.27) (thickness 0.15)) (justify left bottom) hide)
    )
    (property "Val" "1u" (at 156.21 231.1335 90)
      (effects (font (size 1.27 1.27) (thickness 0.15)) (justify right))
    )
    (property "License" "Apache-2.0" (at 176.53 212.09 0)
      (effects (font (size 1.27 1.27) (thickness 0.15)) (justify left bottom) hide)
    )
    (property "Author" "Antmicro" (at 179.07 212.09 0)
      (effects (font (size 1.27 1.27) (thickness 0.15)) (justify left bottom) hide)
    )
    (property "Voltage" "" (at 181.61 212.09 0)
      (effects (font (size 1.27 1.27)) (justify left bottom) hide)
    )
    (property "Dielectric" "" (at 184.15 212.09 0)
      (effects (font (size 1.27 1.27)) (justify left bottom) hide)
    )
    (pin "1")
    (pin "2")
    (instances
      (project "sdi-mipi-bridge"
        (path ""
          (reference "C24") (unit 1)
        )
      )
    )
  )

  (symbol (lib_id "sdi-mipi-bridge:R_0R_0402") (at 158.75 224.79 0) (unit 1)
    (in_bom yes) (on_board yes) (dnp no)
    (property "Reference" "R21" (at 161.29 222.25 0)
      (effects (font (size 1.27 1.27)))
    )
    (property "Value" "R_0R_0402" (at 179.07 237.49 0)
      (effects (font (size 1.27 1.27) (thickness 0.15)) (justify left bottom) hide)
    )
    (property "Footprint" "sdi-mipi-bridge-footprints:R_0402_1005Metric" (at 179.07 240.03 0)
      (effects (font (size 1.27 1.27) (thickness 0.15)) (justify left bottom) hide)
    )
    (property "Datasheet" "https://industrial.panasonic.com/cdbs/www-data/pdf/RDA0000/AOA0000C301.pdf" (at 179.07 242.57 0)
      (effects (font (size 1.27 1.27) (thickness 0.15)) (justify left bottom) hide)
    )
    (property "Manufacturer" "Panasonic" (at 179.07 247.65 0)
      (effects (font (size 1.27 1.27) (thickness 0.15)) (justify left bottom) hide)
    )
    (property "MPN" "ERJ2GE0R00X" (at 179.07 245.11 0)
      (effects (font (size 1.27 1.27) (thickness 0.15)) (justify left bottom) hide)
    )
    (property "Val" "0R" (at 161.29 227.33 0)
      (effects (font (size 1.27 1.27) (thickness 0.15)))
    )
    (property "License" "Apache-2.0" (at 179.07 250.19 0)
      (effects (font (size 1.27 1.27) (thickness 0.15)) (justify left bottom) hide)
    )
    (property "Author" "Antmicro" (at 179.07 252.73 0)
      (effects (font (size 1.27 1.27) (thickness 0.15)) (justify left bottom) hide)
    )
    (property "Tolerance" "~" (at 179.07 234.95 0)
      (effects (font (size 1.27 1.27)) (justify left bottom) hide)
    )
    (property "Current" "1A" (at 179.07 255.27 0)
      (effects (font (size 1.27 1.27) (thickness 0.15)) (justify left bottom) hide)
    )
    (pin "1")
    (pin "2")
    (instances
      (project "sdi-mipi-bridge"
        (path ""
          (reference "R21") (unit 1)
        )
      )
    )
  )

  (symbol (lib_id "sdi-mipi-bridge:GNDREF") (at 144.78 236.22 0) (unit 1)
    (in_bom yes) (on_board yes) (dnp no)
    (property "Reference" "#PWR019" (at 144.78 242.57 0)
      (effects (font (size 1.27 1.27)) hide)
    )
    (property "Value" "GNDREF" (at 144.78 240.03 0)
      (effects (font (size 1.27 1.27)))
    )
    (property "Footprint" "" (at 144.78 236.22 0)
      (effects (font (size 1.27 1.27)) hide)
    )
    (property "Datasheet" "" (at 144.78 236.22 0)
      (effects (font (size 1.27 1.27)) hide)
    )
    (pin "1")
    (instances
      (project "sdi-mipi-bridge"
        (path ""
          (reference "#PWR019") (unit 1)
        )
      )
    )
  )

  (symbol (lib_id "sdi-mipi-bridge:C_1u_0402") (at 168.91 232.41 90) (unit 1)
    (in_bom yes) (on_board yes) (dnp no) (fields_autoplaced)
    (property "Reference" "C28" (at 171.45 228.5935 90)
      (effects (font (size 1.27 1.27)) (justify right))
    )
    (property "Value" "C_1u_0402" (at 179.07 212.09 0)
      (effects (font (size 1.27 1.27) (thickness 0.15)) (justify left bottom) hide)
    )
    (property "Footprint" "sdi-mipi-bridge-footprints:C_0402_1005Metric" (at 181.61 212.09 0)
      (effects (font (size 1.27 1.27) (thickness 0.15)) (justify left bottom) hide)
    )
    (property "Datasheet" " " (at 184.15 212.09 0)
      (effects (font (size 1.27 1.27) (thickness 0.15)) (justify left bottom) hide)
    )
    (property "Manufacturer" "TDK" (at 189.23 212.09 0)
      (effects (font (size 1.27 1.27) (thickness 0.15)) (justify left bottom) hide)
    )
    (property "MPN" "C1005X6S1A105K050BC" (at 186.69 212.09 0)
      (effects (font (size 1.27 1.27) (thickness 0.15)) (justify left bottom) hide)
    )
    (property "Val" "1u" (at 171.45 231.1335 90)
      (effects (font (size 1.27 1.27) (thickness 0.15)) (justify right))
    )
    (property "License" "Apache-2.0" (at 191.77 212.09 0)
      (effects (font (size 1.27 1.27) (thickness 0.15)) (justify left bottom) hide)
    )
    (property "Author" "Antmicro" (at 194.31 212.09 0)
      (effects (font (size 1.27 1.27) (thickness 0.15)) (justify left bottom) hide)
    )
    (property "Voltage" "" (at 196.85 212.09 0)
      (effects (font (size 1.27 1.27)) (justify left bottom) hide)
    )
    (property "Dielectric" "" (at 199.39 212.09 0)
      (effects (font (size 1.27 1.27)) (justify left bottom) hide)
    )
    (pin "1")
    (pin "2")
    (instances
      (project "sdi-mipi-bridge"
        (path ""
          (reference "C28") (unit 1)
        )
      )
    )
  )

  (symbol (lib_id "sdi-mipi-bridge:GNDA") (at 177.8 236.22 0) (unit 1)
    (in_bom yes) (on_board yes) (dnp no)
    (property "Reference" "#PWR026" (at 177.8 242.57 0)
      (effects (font (size 1.27 1.27)) hide)
    )
    (property "Value" "GNDA" (at 177.8 240.03 0)
      (effects (font (size 1.27 1.27)))
    )
    (property "Footprint" "" (at 177.8 236.22 0)
      (effects (font (size 1.27 1.27)) hide)
    )
    (property "Datasheet" "" (at 177.8 236.22 0)
      (effects (font (size 1.27 1.27)) hide)
    )
    (pin "1")
    (instances
      (project "sdi-mipi-bridge"
        (path ""
          (reference "#PWR026") (unit 1)
        )
      )
    )
  )

  (symbol (lib_id "sdi-mipi-bridge:R_0R_0402") (at 158.75 234.95 0) (unit 1)
    (in_bom yes) (on_board yes) (dnp no)
    (property "Reference" "R22" (at 161.29 232.41 0)
      (effects (font (size 1.27 1.27)))
    )
    (property "Value" "R_0R_0402" (at 179.07 247.65 0)
      (effects (font (size 1.27 1.27) (thickness 0.15)) (justify left bottom) hide)
    )
    (property "Footprint" "sdi-mipi-bridge-footprints:R_0402_1005Metric" (at 179.07 250.19 0)
      (effects (font (size 1.27 1.27) (thickness 0.15)) (justify left bottom) hide)
    )
    (property "Datasheet" "https://industrial.panasonic.com/cdbs/www-data/pdf/RDA0000/AOA0000C301.pdf" (at 179.07 252.73 0)
      (effects (font (size 1.27 1.27) (thickness 0.15)) (justify left bottom) hide)
    )
    (property "Manufacturer" "Panasonic" (at 179.07 257.81 0)
      (effects (font (size 1.27 1.27) (thickness 0.15)) (justify left bottom) hide)
    )
    (property "MPN" "ERJ2GE0R00X" (at 179.07 255.27 0)
      (effects (font (size 1.27 1.27) (thickness 0.15)) (justify left bottom) hide)
    )
    (property "Val" "0R" (at 161.29 237.49 0)
      (effects (font (size 1.27 1.27) (thickness 0.15)))
    )
    (property "License" "Apache-2.0" (at 179.07 260.35 0)
      (effects (font (size 1.27 1.27) (thickness 0.15)) (justify left bottom) hide)
    )
    (property "Author" "Antmicro" (at 179.07 262.89 0)
      (effects (font (size 1.27 1.27) (thickness 0.15)) (justify left bottom) hide)
    )
    (property "Tolerance" "~" (at 179.07 245.11 0)
      (effects (font (size 1.27 1.27)) (justify left bottom) hide)
    )
    (property "Current" "1A" (at 179.07 265.43 0)
      (effects (font (size 1.27 1.27) (thickness 0.15)) (justify left bottom) hide)
    )
    (pin "1")
    (pin "2")
    (instances
      (project "sdi-mipi-bridge"
        (path ""
          (reference "R22") (unit 1)
        )
      )
    )
  )

  (symbol (lib_id "sdi-mipi-bridge:C_10n_0402") (at 176.53 271.78 90) (unit 1)
    (in_bom yes) (on_board yes) (dnp no) (fields_autoplaced)
    (property "Reference" "C33" (at 179.07 267.9635 90)
      (effects (font (size 1.27 1.27)) (justify right))
    )
    (property "Value" "C_10n_0402" (at 186.69 251.46 0)
      (effects (font (size 1.27 1.27) (thickness 0.15)) (justify left bottom) hide)
    )
    (property "Footprint" "sdi-mipi-bridge-footprints:C_0402_1005Metric" (at 189.23 251.46 0)
      (effects (font (size 1.27 1.27) (thickness 0.15)) (justify left bottom) hide)
    )
    (property "Datasheet" "https://search.murata.co.jp/Ceramy/image/img/A01X/G101/ENG/GRM155R71H103KA88-01.pdf" (at 191.77 251.46 0)
      (effects (font (size 1.27 1.27) (thickness 0.15)) (justify left bottom) hide)
    )
    (property "Manufacturer" "Murata" (at 196.85 251.46 0)
      (effects (font (size 1.27 1.27) (thickness 0.15)) (justify left bottom) hide)
    )
    (property "MPN" "GRM155R71H103KA88D" (at 194.31 251.46 0)
      (effects (font (size 1.27 1.27) (thickness 0.15)) (justify left bottom) hide)
    )
    (property "Val" "10n" (at 179.07 270.5035 90)
      (effects (font (size 1.27 1.27) (thickness 0.15)) (justify right))
    )
    (property "License" "Apache-2.0" (at 199.39 251.46 0)
      (effects (font (size 1.27 1.27) (thickness 0.15)) (justify left bottom) hide)
    )
    (property "Author" "Antmicro" (at 201.93 251.46 0)
      (effects (font (size 1.27 1.27) (thickness 0.15)) (justify left bottom) hide)
    )
    (property "Voltage" "50V" (at 204.47 251.46 0)
      (effects (font (size 1.27 1.27)) (justify left bottom) hide)
    )
    (property "Dielectric" "X7R" (at 207.01 251.46 0)
      (effects (font (size 1.27 1.27)) (justify left bottom) hide)
    )
    (pin "1")
    (pin "2")
    (instances
      (project "sdi-mipi-bridge"
        (path ""
          (reference "C33") (unit 1)
        )
      )
    )
  )

  (symbol (lib_id "sdi-mipi-bridge:C_10n_0402") (at 144.78 271.78 90) (unit 1)
    (in_bom yes) (on_board yes) (dnp no) (fields_autoplaced)
    (property "Reference" "C20" (at 147.32 267.9635 90)
      (effects (font (size 1.27 1.27)) (justify right))
    )
    (property "Value" "C_10n_0402" (at 154.94 251.46 0)
      (effects (font (size 1.27 1.27) (thickness 0.15)) (justify left bottom) hide)
    )
    (property "Footprint" "sdi-mipi-bridge-footprints:C_0402_1005Metric" (at 157.48 251.46 0)
      (effects (font (size 1.27 1.27) (thickness 0.15)) (justify left bottom) hide)
    )
    (property "Datasheet" "https://search.murata.co.jp/Ceramy/image/img/A01X/G101/ENG/GRM155R71H103KA88-01.pdf" (at 160.02 251.46 0)
      (effects (font (size 1.27 1.27) (thickness 0.15)) (justify left bottom) hide)
    )
    (property "Manufacturer" "Murata" (at 165.1 251.46 0)
      (effects (font (size 1.27 1.27) (thickness 0.15)) (justify left bottom) hide)
    )
    (property "MPN" "GRM155R71H103KA88D" (at 162.56 251.46 0)
      (effects (font (size 1.27 1.27) (thickness 0.15)) (justify left bottom) hide)
    )
    (property "Val" "10n" (at 147.32 270.5035 90)
      (effects (font (size 1.27 1.27) (thickness 0.15)) (justify right))
    )
    (property "License" "Apache-2.0" (at 167.64 251.46 0)
      (effects (font (size 1.27 1.27) (thickness 0.15)) (justify left bottom) hide)
    )
    (property "Author" "Antmicro" (at 170.18 251.46 0)
      (effects (font (size 1.27 1.27) (thickness 0.15)) (justify left bottom) hide)
    )
    (property "Voltage" "50V" (at 172.72 251.46 0)
      (effects (font (size 1.27 1.27)) (justify left bottom) hide)
    )
    (property "Dielectric" "X7R" (at 175.26 251.46 0)
      (effects (font (size 1.27 1.27)) (justify left bottom) hide)
    )
    (pin "1")
    (pin "2")
    (instances
      (project "sdi-mipi-bridge"
        (path ""
          (reference "C20") (unit 1)
        )
      )
    )
  )

  (symbol (lib_id "sdi-mipi-bridge:C_1u_0402") (at 153.67 271.78 90) (unit 1)
    (in_bom yes) (on_board yes) (dnp no) (fields_autoplaced)
    (property "Reference" "C25" (at 156.21 267.9635 90)
      (effects (font (size 1.27 1.27)) (justify right))
    )
    (property "Value" "C_1u_0402" (at 163.83 251.46 0)
      (effects (font (size 1.27 1.27) (thickness 0.15)) (justify left bottom) hide)
    )
    (property "Footprint" "sdi-mipi-bridge-footprints:C_0402_1005Metric" (at 166.37 251.46 0)
      (effects (font (size 1.27 1.27) (thickness 0.15)) (justify left bottom) hide)
    )
    (property "Datasheet" " " (at 168.91 251.46 0)
      (effects (font (size 1.27 1.27) (thickness 0.15)) (justify left bottom) hide)
    )
    (property "Manufacturer" "TDK" (at 173.99 251.46 0)
      (effects (font (size 1.27 1.27) (thickness 0.15)) (justify left bottom) hide)
    )
    (property "MPN" "C1005X6S1A105K050BC" (at 171.45 251.46 0)
      (effects (font (size 1.27 1.27) (thickness 0.15)) (justify left bottom) hide)
    )
    (property "Val" "1u" (at 156.21 270.5035 90)
      (effects (font (size 1.27 1.27) (thickness 0.15)) (justify right))
    )
    (property "License" "Apache-2.0" (at 176.53 251.46 0)
      (effects (font (size 1.27 1.27) (thickness 0.15)) (justify left bottom) hide)
    )
    (property "Author" "Antmicro" (at 179.07 251.46 0)
      (effects (font (size 1.27 1.27) (thickness 0.15)) (justify left bottom) hide)
    )
    (property "Voltage" "" (at 181.61 251.46 0)
      (effects (font (size 1.27 1.27)) (justify left bottom) hide)
    )
    (property "Dielectric" "" (at 184.15 251.46 0)
      (effects (font (size 1.27 1.27)) (justify left bottom) hide)
    )
    (pin "1")
    (pin "2")
    (instances
      (project "sdi-mipi-bridge"
        (path ""
          (reference "C25") (unit 1)
        )
      )
    )
  )

  (symbol (lib_id "sdi-mipi-bridge:R_0R_0402") (at 158.75 264.16 0) (unit 1)
    (in_bom yes) (on_board yes) (dnp no) (fields_autoplaced)
    (property "Reference" "R23" (at 161.29 257.81 0)
      (effects (font (size 1.27 1.27)))
    )
    (property "Value" "R_0R_0402" (at 179.07 276.86 0)
      (effects (font (size 1.27 1.27) (thickness 0.15)) (justify left bottom) hide)
    )
    (property "Footprint" "sdi-mipi-bridge-footprints:R_0402_1005Metric" (at 179.07 279.4 0)
      (effects (font (size 1.27 1.27) (thickness 0.15)) (justify left bottom) hide)
    )
    (property "Datasheet" "https://industrial.panasonic.com/cdbs/www-data/pdf/RDA0000/AOA0000C301.pdf" (at 179.07 281.94 0)
      (effects (font (size 1.27 1.27) (thickness 0.15)) (justify left bottom) hide)
    )
    (property "Manufacturer" "Panasonic" (at 179.07 287.02 0)
      (effects (font (size 1.27 1.27) (thickness 0.15)) (justify left bottom) hide)
    )
    (property "MPN" "ERJ2GE0R00X" (at 179.07 284.48 0)
      (effects (font (size 1.27 1.27) (thickness 0.15)) (justify left bottom) hide)
    )
    (property "Val" "0R" (at 161.29 260.35 0)
      (effects (font (size 1.27 1.27) (thickness 0.15)))
    )
    (property "License" "Apache-2.0" (at 179.07 289.56 0)
      (effects (font (size 1.27 1.27) (thickness 0.15)) (justify left bottom) hide)
    )
    (property "Author" "Antmicro" (at 179.07 292.1 0)
      (effects (font (size 1.27 1.27) (thickness 0.15)) (justify left bottom) hide)
    )
    (property "Tolerance" "~" (at 179.07 274.32 0)
      (effects (font (size 1.27 1.27)) (justify left bottom) hide)
    )
    (property "Current" "1A" (at 179.07 294.64 0)
      (effects (font (size 1.27 1.27) (thickness 0.15)) (justify left bottom) hide)
    )
    (pin "1")
    (pin "2")
    (instances
      (project "sdi-mipi-bridge"
        (path ""
          (reference "R23") (unit 1)
        )
      )
    )
  )

  (symbol (lib_id "sdi-mipi-bridge:GNDREF") (at 144.78 271.78 0) (unit 1)
    (in_bom yes) (on_board yes) (dnp no)
    (property "Reference" "#PWR021" (at 144.78 278.13 0)
      (effects (font (size 1.27 1.27)) hide)
    )
    (property "Value" "GNDREF" (at 144.78 275.59 0)
      (effects (font (size 1.27 1.27)))
    )
    (property "Footprint" "" (at 144.78 271.78 0)
      (effects (font (size 1.27 1.27)) hide)
    )
    (property "Datasheet" "" (at 144.78 271.78 0)
      (effects (font (size 1.27 1.27)) hide)
    )
    (pin "1")
    (instances
      (project "sdi-mipi-bridge"
        (path ""
          (reference "#PWR021") (unit 1)
        )
      )
    )
  )

  (symbol (lib_id "sdi-mipi-bridge:C_1u_0402") (at 168.91 271.78 90) (unit 1)
    (in_bom yes) (on_board yes) (dnp no) (fields_autoplaced)
    (property "Reference" "C29" (at 171.45 267.9635 90)
      (effects (font (size 1.27 1.27)) (justify right))
    )
    (property "Value" "C_1u_0402" (at 179.07 251.46 0)
      (effects (font (size 1.27 1.27) (thickness 0.15)) (justify left bottom) hide)
    )
    (property "Footprint" "sdi-mipi-bridge-footprints:C_0402_1005Metric" (at 181.61 251.46 0)
      (effects (font (size 1.27 1.27) (thickness 0.15)) (justify left bottom) hide)
    )
    (property "Datasheet" " " (at 184.15 251.46 0)
      (effects (font (size 1.27 1.27) (thickness 0.15)) (justify left bottom) hide)
    )
    (property "Manufacturer" "TDK" (at 189.23 251.46 0)
      (effects (font (size 1.27 1.27) (thickness 0.15)) (justify left bottom) hide)
    )
    (property "MPN" "C1005X6S1A105K050BC" (at 186.69 251.46 0)
      (effects (font (size 1.27 1.27) (thickness 0.15)) (justify left bottom) hide)
    )
    (property "Val" "1u" (at 171.45 270.5035 90)
      (effects (font (size 1.27 1.27) (thickness 0.15)) (justify right))
    )
    (property "License" "Apache-2.0" (at 191.77 251.46 0)
      (effects (font (size 1.27 1.27) (thickness 0.15)) (justify left bottom) hide)
    )
    (property "Author" "Antmicro" (at 194.31 251.46 0)
      (effects (font (size 1.27 1.27) (thickness 0.15)) (justify left bottom) hide)
    )
    (property "Voltage" "" (at 196.85 251.46 0)
      (effects (font (size 1.27 1.27)) (justify left bottom) hide)
    )
    (property "Dielectric" "" (at 199.39 251.46 0)
      (effects (font (size 1.27 1.27)) (justify left bottom) hide)
    )
    (pin "1")
    (pin "2")
    (instances
      (project "sdi-mipi-bridge"
        (path ""
          (reference "C29") (unit 1)
        )
      )
    )
  )

  (symbol (lib_id "sdi-mipi-bridge:GNDA") (at 168.91 271.78 0) (unit 1)
    (in_bom yes) (on_board yes) (dnp no)
    (property "Reference" "#PWR028" (at 168.91 278.13 0)
      (effects (font (size 1.27 1.27)) hide)
    )
    (property "Value" "GNDA" (at 168.91 275.59 0)
      (effects (font (size 1.27 1.27)))
    )
    (property "Footprint" "" (at 168.91 271.78 0)
      (effects (font (size 1.27 1.27)) hide)
    )
    (property "Datasheet" "" (at 168.91 271.78 0)
      (effects (font (size 1.27 1.27)) hide)
    )
    (pin "1")
    (instances
      (project "sdi-mipi-bridge"
        (path ""
          (reference "#PWR028") (unit 1)
        )
      )
    )
  )

  (symbol (lib_id "sdi-mipi-bridge:C_10n_0402") (at 34.29 337.82 90) (unit 1)
    (in_bom yes) (on_board yes) (dnp no) (fields_autoplaced)
    (property "Reference" "C3" (at 31.75 334.0035 90)
      (effects (font (size 1.27 1.27)) (justify left))
    )
    (property "Value" "C_10n_0402" (at 44.45 317.5 0)
      (effects (font (size 1.27 1.27) (thickness 0.15)) (justify left bottom) hide)
    )
    (property "Footprint" "sdi-mipi-bridge-footprints:C_0402_1005Metric" (at 46.99 317.5 0)
      (effects (font (size 1.27 1.27) (thickness 0.15)) (justify left bottom) hide)
    )
    (property "Datasheet" "https://search.murata.co.jp/Ceramy/image/img/A01X/G101/ENG/GRM155R71H103KA88-01.pdf" (at 49.53 317.5 0)
      (effects (font (size 1.27 1.27) (thickness 0.15)) (justify left bottom) hide)
    )
    (property "Manufacturer" "Murata" (at 54.61 317.5 0)
      (effects (font (size 1.27 1.27) (thickness 0.15)) (justify left bottom) hide)
    )
    (property "MPN" "GRM155R71H103KA88D" (at 52.07 317.5 0)
      (effects (font (size 1.27 1.27) (thickness 0.15)) (justify left bottom) hide)
    )
    (property "Val" "10n" (at 31.75 336.5435 90)
      (effects (font (size 1.27 1.27) (thickness 0.15)) (justify left))
    )
    (property "License" "Apache-2.0" (at 57.15 317.5 0)
      (effects (font (size 1.27 1.27) (thickness 0.15)) (justify left bottom) hide)
    )
    (property "Author" "Antmicro" (at 59.69 317.5 0)
      (effects (font (size 1.27 1.27) (thickness 0.15)) (justify left bottom) hide)
    )
    (property "Voltage" "50V" (at 62.23 317.5 0)
      (effects (font (size 1.27 1.27)) (justify left bottom) hide)
    )
    (property "Dielectric" "X7R" (at 64.77 317.5 0)
      (effects (font (size 1.27 1.27)) (justify left bottom) hide)
    )
    (pin "1")
    (pin "2")
    (instances
      (project "sdi-mipi-bridge"
        (path ""
          (reference "C3") (unit 1)
        )
      )
    )
  )

  (symbol (lib_id "sdi-mipi-bridge:C_10n_0402") (at 41.91 337.82 90) (unit 1)
    (in_bom yes) (on_board yes) (dnp no) (fields_autoplaced)
    (property "Reference" "C5" (at 44.45 334.0035 90)
      (effects (font (size 1.27 1.27)) (justify right))
    )
    (property "Value" "C_10n_0402" (at 52.07 317.5 0)
      (effects (font (size 1.27 1.27) (thickness 0.15)) (justify left bottom) hide)
    )
    (property "Footprint" "sdi-mipi-bridge-footprints:C_0402_1005Metric" (at 54.61 317.5 0)
      (effects (font (size 1.27 1.27) (thickness 0.15)) (justify left bottom) hide)
    )
    (property "Datasheet" "https://search.murata.co.jp/Ceramy/image/img/A01X/G101/ENG/GRM155R71H103KA88-01.pdf" (at 57.15 317.5 0)
      (effects (font (size 1.27 1.27) (thickness 0.15)) (justify left bottom) hide)
    )
    (property "Manufacturer" "Murata" (at 62.23 317.5 0)
      (effects (font (size 1.27 1.27) (thickness 0.15)) (justify left bottom) hide)
    )
    (property "MPN" "GRM155R71H103KA88D" (at 59.69 317.5 0)
      (effects (font (size 1.27 1.27) (thickness 0.15)) (justify left bottom) hide)
    )
    (property "Val" "10n" (at 44.45 336.5435 90)
      (effects (font (size 1.27 1.27) (thickness 0.15)) (justify right))
    )
    (property "License" "Apache-2.0" (at 64.77 317.5 0)
      (effects (font (size 1.27 1.27) (thickness 0.15)) (justify left bottom) hide)
    )
    (property "Author" "Antmicro" (at 67.31 317.5 0)
      (effects (font (size 1.27 1.27) (thickness 0.15)) (justify left bottom) hide)
    )
    (property "Voltage" "50V" (at 69.85 317.5 0)
      (effects (font (size 1.27 1.27)) (justify left bottom) hide)
    )
    (property "Dielectric" "X7R" (at 72.39 317.5 0)
      (effects (font (size 1.27 1.27)) (justify left bottom) hide)
    )
    (pin "1")
    (pin "2")
    (instances
      (project "sdi-mipi-bridge"
        (path ""
          (reference "C5") (unit 1)
        )
      )
    )
  )

  (symbol (lib_id "sdi-mipi-bridge:C_10n_0402") (at 49.53 337.82 90) (unit 1)
    (in_bom yes) (on_board yes) (dnp no) (fields_autoplaced)
    (property "Reference" "C7" (at 52.07 334.0035 90)
      (effects (font (size 1.27 1.27)) (justify right))
    )
    (property "Value" "C_10n_0402" (at 59.69 317.5 0)
      (effects (font (size 1.27 1.27) (thickness 0.15)) (justify left bottom) hide)
    )
    (property "Footprint" "sdi-mipi-bridge-footprints:C_0402_1005Metric" (at 62.23 317.5 0)
      (effects (font (size 1.27 1.27) (thickness 0.15)) (justify left bottom) hide)
    )
    (property "Datasheet" "https://search.murata.co.jp/Ceramy/image/img/A01X/G101/ENG/GRM155R71H103KA88-01.pdf" (at 64.77 317.5 0)
      (effects (font (size 1.27 1.27) (thickness 0.15)) (justify left bottom) hide)
    )
    (property "Manufacturer" "Murata" (at 69.85 317.5 0)
      (effects (font (size 1.27 1.27) (thickness 0.15)) (justify left bottom) hide)
    )
    (property "MPN" "GRM155R71H103KA88D" (at 67.31 317.5 0)
      (effects (font (size 1.27 1.27) (thickness 0.15)) (justify left bottom) hide)
    )
    (property "Val" "10n" (at 52.07 336.5435 90)
      (effects (font (size 1.27 1.27) (thickness 0.15)) (justify right))
    )
    (property "License" "Apache-2.0" (at 72.39 317.5 0)
      (effects (font (size 1.27 1.27) (thickness 0.15)) (justify left bottom) hide)
    )
    (property "Author" "Antmicro" (at 74.93 317.5 0)
      (effects (font (size 1.27 1.27) (thickness 0.15)) (justify left bottom) hide)
    )
    (property "Voltage" "50V" (at 77.47 317.5 0)
      (effects (font (size 1.27 1.27)) (justify left bottom) hide)
    )
    (property "Dielectric" "X7R" (at 80.01 317.5 0)
      (effects (font (size 1.27 1.27)) (justify left bottom) hide)
    )
    (pin "1")
    (pin "2")
    (instances
      (project "sdi-mipi-bridge"
        (path ""
          (reference "C7") (unit 1)
        )
      )
    )
  )

  (symbol (lib_id "sdi-mipi-bridge:C_10n_0402") (at 57.15 337.82 90) (unit 1)
    (in_bom yes) (on_board yes) (dnp no) (fields_autoplaced)
    (property "Reference" "C9" (at 59.69 334.0035 90)
      (effects (font (size 1.27 1.27)) (justify right))
    )
    (property "Value" "C_10n_0402" (at 67.31 317.5 0)
      (effects (font (size 1.27 1.27) (thickness 0.15)) (justify left bottom) hide)
    )
    (property "Footprint" "sdi-mipi-bridge-footprints:C_0402_1005Metric" (at 69.85 317.5 0)
      (effects (font (size 1.27 1.27) (thickness 0.15)) (justify left bottom) hide)
    )
    (property "Datasheet" "https://search.murata.co.jp/Ceramy/image/img/A01X/G101/ENG/GRM155R71H103KA88-01.pdf" (at 72.39 317.5 0)
      (effects (font (size 1.27 1.27) (thickness 0.15)) (justify left bottom) hide)
    )
    (property "Manufacturer" "Murata" (at 77.47 317.5 0)
      (effects (font (size 1.27 1.27) (thickness 0.15)) (justify left bottom) hide)
    )
    (property "MPN" "GRM155R71H103KA88D" (at 74.93 317.5 0)
      (effects (font (size 1.27 1.27) (thickness 0.15)) (justify left bottom) hide)
    )
    (property "Val" "10n" (at 59.69 336.5435 90)
      (effects (font (size 1.27 1.27) (thickness 0.15)) (justify right))
    )
    (property "License" "Apache-2.0" (at 80.01 317.5 0)
      (effects (font (size 1.27 1.27) (thickness 0.15)) (justify left bottom) hide)
    )
    (property "Author" "Antmicro" (at 82.55 317.5 0)
      (effects (font (size 1.27 1.27) (thickness 0.15)) (justify left bottom) hide)
    )
    (property "Voltage" "50V" (at 85.09 317.5 0)
      (effects (font (size 1.27 1.27)) (justify left bottom) hide)
    )
    (property "Dielectric" "X7R" (at 87.63 317.5 0)
      (effects (font (size 1.27 1.27)) (justify left bottom) hide)
    )
    (pin "1")
    (pin "2")
    (instances
      (project "sdi-mipi-bridge"
        (path ""
          (reference "C9") (unit 1)
        )
      )
    )
  )

  (symbol (lib_id "sdi-mipi-bridge:C_10n_0402") (at 76.2 337.82 90) (unit 1)
    (in_bom yes) (on_board yes) (dnp no)
    (property "Reference" "C12" (at 77.47 334.01 90)
      (effects (font (size 1.27 1.27)) (justify right))
    )
    (property "Value" "C_10n_0402" (at 86.36 317.5 0)
      (effects (font (size 1.27 1.27) (thickness 0.15)) (justify left bottom) hide)
    )
    (property "Footprint" "sdi-mipi-bridge-footprints:C_0402_1005Metric" (at 88.9 317.5 0)
      (effects (font (size 1.27 1.27) (thickness 0.15)) (justify left bottom) hide)
    )
    (property "Datasheet" "https://search.murata.co.jp/Ceramy/image/img/A01X/G101/ENG/GRM155R71H103KA88-01.pdf" (at 91.44 317.5 0)
      (effects (font (size 1.27 1.27) (thickness 0.15)) (justify left bottom) hide)
    )
    (property "Manufacturer" "Murata" (at 96.52 317.5 0)
      (effects (font (size 1.27 1.27) (thickness 0.15)) (justify left bottom) hide)
    )
    (property "MPN" "GRM155R71H103KA88D" (at 93.98 317.5 0)
      (effects (font (size 1.27 1.27) (thickness 0.15)) (justify left bottom) hide)
    )
    (property "Val" "10n" (at 77.47 336.55 90)
      (effects (font (size 1.27 1.27) (thickness 0.15)) (justify right))
    )
    (property "License" "Apache-2.0" (at 99.06 317.5 0)
      (effects (font (size 1.27 1.27) (thickness 0.15)) (justify left bottom) hide)
    )
    (property "Author" "Antmicro" (at 101.6 317.5 0)
      (effects (font (size 1.27 1.27) (thickness 0.15)) (justify left bottom) hide)
    )
    (property "Voltage" "50V" (at 104.14 317.5 0)
      (effects (font (size 1.27 1.27)) (justify left bottom) hide)
    )
    (property "Dielectric" "X7R" (at 106.68 317.5 0)
      (effects (font (size 1.27 1.27)) (justify left bottom) hide)
    )
    (pin "1")
    (pin "2")
    (instances
      (project "sdi-mipi-bridge"
        (path ""
          (reference "C12") (unit 1)
        )
      )
    )
  )

  (symbol (lib_id "sdi-mipi-bridge:C_10n_0402") (at 83.82 337.82 90) (unit 1)
    (in_bom yes) (on_board yes) (dnp no)
    (property "Reference" "C14" (at 85.09 334.01 90)
      (effects (font (size 1.27 1.27)) (justify right))
    )
    (property "Value" "C_10n_0402" (at 93.98 317.5 0)
      (effects (font (size 1.27 1.27) (thickness 0.15)) (justify left bottom) hide)
    )
    (property "Footprint" "sdi-mipi-bridge-footprints:C_0402_1005Metric" (at 96.52 317.5 0)
      (effects (font (size 1.27 1.27) (thickness 0.15)) (justify left bottom) hide)
    )
    (property "Datasheet" "https://search.murata.co.jp/Ceramy/image/img/A01X/G101/ENG/GRM155R71H103KA88-01.pdf" (at 99.06 317.5 0)
      (effects (font (size 1.27 1.27) (thickness 0.15)) (justify left bottom) hide)
    )
    (property "Manufacturer" "Murata" (at 104.14 317.5 0)
      (effects (font (size 1.27 1.27) (thickness 0.15)) (justify left bottom) hide)
    )
    (property "MPN" "GRM155R71H103KA88D" (at 101.6 317.5 0)
      (effects (font (size 1.27 1.27) (thickness 0.15)) (justify left bottom) hide)
    )
    (property "Val" "10n" (at 85.09 336.55 90)
      (effects (font (size 1.27 1.27) (thickness 0.15)) (justify right))
    )
    (property "License" "Apache-2.0" (at 106.68 317.5 0)
      (effects (font (size 1.27 1.27) (thickness 0.15)) (justify left bottom) hide)
    )
    (property "Author" "Antmicro" (at 109.22 317.5 0)
      (effects (font (size 1.27 1.27) (thickness 0.15)) (justify left bottom) hide)
    )
    (property "Voltage" "50V" (at 111.76 317.5 0)
      (effects (font (size 1.27 1.27)) (justify left bottom) hide)
    )
    (property "Dielectric" "X7R" (at 114.3 317.5 0)
      (effects (font (size 1.27 1.27)) (justify left bottom) hide)
    )
    (pin "1")
    (pin "2")
    (instances
      (project "sdi-mipi-bridge"
        (path ""
          (reference "C14") (unit 1)
        )
      )
    )
  )

  (symbol (lib_id "sdi-mipi-bridge:C_10n_0402") (at 91.44 337.82 90) (unit 1)
    (in_bom yes) (on_board yes) (dnp no)
    (property "Reference" "C17" (at 92.71 334.01 90)
      (effects (font (size 1.27 1.27)) (justify right))
    )
    (property "Value" "C_10n_0402" (at 101.6 317.5 0)
      (effects (font (size 1.27 1.27) (thickness 0.15)) (justify left bottom) hide)
    )
    (property "Footprint" "sdi-mipi-bridge-footprints:C_0402_1005Metric" (at 104.14 317.5 0)
      (effects (font (size 1.27 1.27) (thickness 0.15)) (justify left bottom) hide)
    )
    (property "Datasheet" "https://search.murata.co.jp/Ceramy/image/img/A01X/G101/ENG/GRM155R71H103KA88-01.pdf" (at 106.68 317.5 0)
      (effects (font (size 1.27 1.27) (thickness 0.15)) (justify left bottom) hide)
    )
    (property "Manufacturer" "Murata" (at 111.76 317.5 0)
      (effects (font (size 1.27 1.27) (thickness 0.15)) (justify left bottom) hide)
    )
    (property "MPN" "GRM155R71H103KA88D" (at 109.22 317.5 0)
      (effects (font (size 1.27 1.27) (thickness 0.15)) (justify left bottom) hide)
    )
    (property "Val" "10n" (at 92.71 336.55 90)
      (effects (font (size 1.27 1.27) (thickness 0.15)) (justify right))
    )
    (property "License" "Apache-2.0" (at 114.3 317.5 0)
      (effects (font (size 1.27 1.27) (thickness 0.15)) (justify left bottom) hide)
    )
    (property "Author" "Antmicro" (at 116.84 317.5 0)
      (effects (font (size 1.27 1.27) (thickness 0.15)) (justify left bottom) hide)
    )
    (property "Voltage" "50V" (at 119.38 317.5 0)
      (effects (font (size 1.27 1.27)) (justify left bottom) hide)
    )
    (property "Dielectric" "X7R" (at 121.92 317.5 0)
      (effects (font (size 1.27 1.27)) (justify left bottom) hide)
    )
    (pin "1")
    (pin "2")
    (instances
      (project "sdi-mipi-bridge"
        (path ""
          (reference "C17") (unit 1)
        )
      )
    )
  )

  (symbol (lib_id "sdi-mipi-bridge:GNDA") (at 76.2 337.82 0) (unit 1)
    (in_bom yes) (on_board yes) (dnp no)
    (property "Reference" "#PWR012" (at 76.2 344.17 0)
      (effects (font (size 1.27 1.27)) hide)
    )
    (property "Value" "GNDA" (at 76.327 342.2142 0)
      (effects (font (size 1.27 1.27)))
    )
    (property "Footprint" "" (at 76.2 337.82 0)
      (effects (font (size 1.27 1.27)) hide)
    )
    (property "Datasheet" "" (at 76.2 337.82 0)
      (effects (font (size 1.27 1.27)) hide)
    )
    (pin "1")
    (instances
      (project "sdi-mipi-bridge"
        (path ""
          (reference "#PWR012") (unit 1)
        )
      )
    )
  )

  (symbol (lib_id "sdi-mipi-bridge:GNDREF") (at 34.29 337.82 0) (unit 1)
    (in_bom yes) (on_board yes) (dnp no)
    (property "Reference" "#PWR05" (at 34.29 344.17 0)
      (effects (font (size 1.27 1.27)) hide)
    )
    (property "Value" "GNDREF" (at 34.417 342.2142 0)
      (effects (font (size 1.27 1.27)))
    )
    (property "Footprint" "" (at 34.29 337.82 0)
      (effects (font (size 1.27 1.27)) hide)
    )
    (property "Datasheet" "" (at 34.29 337.82 0)
      (effects (font (size 1.27 1.27)) hide)
    )
    (pin "1")
    (instances
      (project "sdi-mipi-bridge"
        (path ""
          (reference "#PWR05") (unit 1)
        )
      )
    )
  )

  (symbol (lib_id "sdi-mipi-bridge:+3.3VA") (at 76.2 327.66 0) (unit 1)
    (in_bom yes) (on_board yes) (dnp no)
    (property "Reference" "#PWR011" (at 76.2 331.47 0)
      (effects (font (size 1.27 1.27)) hide)
    )
    (property "Value" "+3.3VA" (at 76.581 323.2658 0)
      (effects (font (size 1.27 1.27)))
    )
    (property "Footprint" "" (at 76.2 327.66 0)
      (effects (font (size 1.27 1.27)) hide)
    )
    (property "Datasheet" "" (at 76.2 327.66 0)
      (effects (font (size 1.27 1.27)) hide)
    )
    (pin "1")
    (instances
      (project "sdi-mipi-bridge"
        (path ""
          (reference "#PWR011") (unit 1)
        )
      )
    )
  )

  (symbol (lib_id "sdi-mipi-bridge:C_33u_0603") (at 325.12 152.4 0) (unit 1)
    (in_bom yes) (on_board yes) (dnp no) (fields_autoplaced)
    (property "Reference" "C58" (at 327.66 153.1365 0)
      (effects (font (size 1.27 1.27)) (justify left))
    )
    (property "Value" "C_33u_0603" (at 339.09 157.48 0)
      (effects (font (size 1.27 1.27) (thickness 0.15)) (justify left bottom) hide)
    )
    (property "Footprint" "sdi-mipi-bridge-footprints:C_0603_1608Metric" (at 339.09 160.02 0)
      (effects (font (size 1.27 1.27) (thickness 0.15)) (justify left bottom) hide)
    )
    (property "Datasheet" " " (at 339.09 162.56 0)
      (effects (font (size 1.27 1.27) (thickness 0.15)) (justify left bottom) hide)
    )
    (property "Manufacturer" "AVX" (at 339.09 167.64 0)
      (effects (font (size 1.27 1.27) (thickness 0.15)) (justify left bottom) hide)
    )
    (property "MPN" "F980G336MMA" (at 339.09 165.1 0)
      (effects (font (size 1.27 1.27) (thickness 0.15)) (justify left bottom) hide)
    )
    (property "Val" "33u" (at 327.66 155.6765 0)
      (effects (font (size 1.27 1.27) (thickness 0.15)) (justify left))
    )
    (property "License" "Apache-2.0" (at 339.09 170.18 0)
      (effects (font (size 1.27 1.27) (thickness 0.15)) (justify left bottom) hide)
    )
    (property "Author" "Antmicro" (at 339.09 172.72 0)
      (effects (font (size 1.27 1.27) (thickness 0.15)) (justify left bottom) hide)
    )
    (property "Voltage" "" (at 339.09 175.26 0)
      (effects (font (size 1.27 1.27)) (justify left bottom) hide)
    )
    (property "Dielectric" "" (at 339.09 177.8 0)
      (effects (font (size 1.27 1.27)) (justify left bottom) hide)
    )
    (pin "1")
    (pin "2")
    (instances
      (project "sdi-mipi-bridge"
        (path ""
          (reference "C58") (unit 1)
        )
      )
    )
  )

  (symbol (lib_id "sdi-mipi-bridge:R_105R_0402") (at 325.12 142.24 270) (unit 1)
    (in_bom yes) (on_board yes) (dnp no) (fields_autoplaced)
    (property "Reference" "R30" (at 327.66 143.5099 90)
      (effects (font (size 1.27 1.27)) (justify left))
    )
    (property "Value" "R_105R_0402" (at 312.42 162.56 0)
      (effects (font (size 1.27 1.27) (thickness 0.15)) (justify left bottom) hide)
    )
    (property "Footprint" "sdi-mipi-bridge-footprints:R_0402_1005Metric" (at 309.88 162.56 0)
      (effects (font (size 1.27 1.27) (thickness 0.15)) (justify left bottom) hide)
    )
    (property "Datasheet" "https://www.bourns.com/docs/product-datasheets/cr.pdf" (at 307.34 162.56 0)
      (effects (font (size 1.27 1.27) (thickness 0.15)) (justify left bottom) hide)
    )
    (property "Manufacturer" "Bourns" (at 302.26 162.56 0)
      (effects (font (size 1.27 1.27) (thickness 0.15)) (justify left bottom) hide)
    )
    (property "MPN" "CR0402-FX-1050GLF" (at 304.8 162.56 0)
      (effects (font (size 1.27 1.27) (thickness 0.15)) (justify left bottom) hide)
    )
    (property "Val" "105R" (at 327.66 146.0499 90)
      (effects (font (size 1.27 1.27) (thickness 0.15)) (justify left))
    )
    (property "License" "Apache-2.0" (at 299.72 162.56 0)
      (effects (font (size 1.27 1.27) (thickness 0.15)) (justify left bottom) hide)
    )
    (property "Author" "Antmicro" (at 297.18 162.56 0)
      (effects (font (size 1.27 1.27) (thickness 0.15)) (justify left bottom) hide)
    )
    (property "Tolerance" "1%" (at 314.96 162.56 0)
      (effects (font (size 1.27 1.27)) (justify left bottom) hide)
    )
    (pin "1")
    (pin "2")
    (instances
      (project "sdi-mipi-bridge"
        (path ""
          (reference "R30") (unit 1)
        )
      )
    )
  )

  (symbol (lib_id "sdi-mipi-bridge:GNDA") (at 325.12 157.48 0) (unit 1)
    (in_bom yes) (on_board yes) (dnp no)
    (property "Reference" "#PWR053" (at 325.12 163.83 0)
      (effects (font (size 1.27 1.27)) hide)
    )
    (property "Value" "GNDA" (at 325.247 161.8742 0)
      (effects (font (size 1.27 1.27)))
    )
    (property "Footprint" "" (at 325.12 157.48 0)
      (effects (font (size 1.27 1.27)) hide)
    )
    (property "Datasheet" "" (at 325.12 157.48 0)
      (effects (font (size 1.27 1.27)) hide)
    )
    (pin "1")
    (instances
      (project "sdi-mipi-bridge"
        (path ""
          (reference "#PWR053") (unit 1)
        )
      )
    )
  )

  (symbol (lib_id "sdi-mipi-bridge:R_2k2_0402") (at 530.86 156.21 270) (unit 1)
    (in_bom yes) (on_board yes) (dnp no)
    (property "Reference" "R86" (at 532.13 157.48 90)
      (effects (font (size 1.27 1.27)) (justify left))
    )
    (property "Value" "R_2k2_0402" (at 518.16 176.53 0)
      (effects (font (size 1.27 1.27) (thickness 0.15)) (justify left bottom) hide)
    )
    (property "Footprint" "sdi-mipi-bridge-footprints:R_0402_1005Metric" (at 515.62 176.53 0)
      (effects (font (size 1.27 1.27) (thickness 0.15)) (justify left bottom) hide)
    )
    (property "Datasheet" "https://www.bourns.com/docs/product-datasheets/cr.pdf" (at 513.08 176.53 0)
      (effects (font (size 1.27 1.27) (thickness 0.15)) (justify left bottom) hide)
    )
    (property "Manufacturer" "Bourns" (at 508 176.53 0)
      (effects (font (size 1.27 1.27) (thickness 0.15)) (justify left bottom) hide)
    )
    (property "MPN" "CR0402-FX-2201GLF" (at 510.54 176.53 0)
      (effects (font (size 1.27 1.27) (thickness 0.15)) (justify left bottom) hide)
    )
    (property "Val" "2k2" (at 532.13 160.02 90)
      (effects (font (size 1.27 1.27) (thickness 0.15)) (justify left))
    )
    (property "License" "Apache-2.0" (at 505.46 176.53 0)
      (effects (font (size 1.27 1.27) (thickness 0.15)) (justify left bottom) hide)
    )
    (property "Author" "Antmicro" (at 502.92 176.53 0)
      (effects (font (size 1.27 1.27) (thickness 0.15)) (justify left bottom) hide)
    )
    (property "Tolerance" "1%" (at 520.7 176.53 0)
      (effects (font (size 1.27 1.27)) (justify left bottom) hide)
    )
    (property "DNP" "DNP" (at 530.86 156.21 0)
      (effects (font (size 1.27 1.27)) hide)
    )
    (pin "1")
    (pin "2")
    (instances
      (project "sdi-mipi-bridge"
        (path ""
          (reference "R86") (unit 1)
        )
      )
    )
  )

  (symbol (lib_id "sdi-mipi-bridge:R_2k2_0402") (at 537.21 156.21 270) (unit 1)
    (in_bom yes) (on_board yes) (dnp no)
    (property "Reference" "R87" (at 538.48 157.48 90)
      (effects (font (size 1.27 1.27)) (justify left))
    )
    (property "Value" "R_2k2_0402" (at 524.51 176.53 0)
      (effects (font (size 1.27 1.27) (thickness 0.15)) (justify left bottom) hide)
    )
    (property "Footprint" "sdi-mipi-bridge-footprints:R_0402_1005Metric" (at 521.97 176.53 0)
      (effects (font (size 1.27 1.27) (thickness 0.15)) (justify left bottom) hide)
    )
    (property "Datasheet" "https://www.bourns.com/docs/product-datasheets/cr.pdf" (at 519.43 176.53 0)
      (effects (font (size 1.27 1.27) (thickness 0.15)) (justify left bottom) hide)
    )
    (property "Manufacturer" "Bourns" (at 514.35 176.53 0)
      (effects (font (size 1.27 1.27) (thickness 0.15)) (justify left bottom) hide)
    )
    (property "MPN" "CR0402-FX-2201GLF" (at 516.89 176.53 0)
      (effects (font (size 1.27 1.27) (thickness 0.15)) (justify left bottom) hide)
    )
    (property "Val" "2k2" (at 538.48 160.02 90)
      (effects (font (size 1.27 1.27) (thickness 0.15)) (justify left))
    )
    (property "License" "Apache-2.0" (at 511.81 176.53 0)
      (effects (font (size 1.27 1.27) (thickness 0.15)) (justify left bottom) hide)
    )
    (property "Author" "Antmicro" (at 509.27 176.53 0)
      (effects (font (size 1.27 1.27) (thickness 0.15)) (justify left bottom) hide)
    )
    (property "Tolerance" "1%" (at 527.05 176.53 0)
      (effects (font (size 1.27 1.27)) (justify left bottom) hide)
    )
    (property "DNP" "DNP" (at 537.21 156.21 0)
      (effects (font (size 1.27 1.27)) hide)
    )
    (pin "1")
    (pin "2")
    (instances
      (project "sdi-mipi-bridge"
        (path ""
          (reference "R87") (unit 1)
        )
      )
    )
  )

  (symbol (lib_id "sdi-mipi-bridge:R_2k2_0402") (at 543.56 156.21 270) (unit 1)
    (in_bom yes) (on_board yes) (dnp no)
    (property "Reference" "R94" (at 544.83 157.48 90)
      (effects (font (size 1.27 1.27)) (justify left))
    )
    (property "Value" "R_2k2_0402" (at 530.86 176.53 0)
      (effects (font (size 1.27 1.27) (thickness 0.15)) (justify left bottom) hide)
    )
    (property "Footprint" "sdi-mipi-bridge-footprints:R_0402_1005Metric" (at 528.32 176.53 0)
      (effects (font (size 1.27 1.27) (thickness 0.15)) (justify left bottom) hide)
    )
    (property "Datasheet" "https://www.bourns.com/docs/product-datasheets/cr.pdf" (at 525.78 176.53 0)
      (effects (font (size 1.27 1.27) (thickness 0.15)) (justify left bottom) hide)
    )
    (property "Manufacturer" "Bourns" (at 520.7 176.53 0)
      (effects (font (size 1.27 1.27) (thickness 0.15)) (justify left bottom) hide)
    )
    (property "MPN" "CR0402-FX-2201GLF" (at 523.24 176.53 0)
      (effects (font (size 1.27 1.27) (thickness 0.15)) (justify left bottom) hide)
    )
    (property "Val" "2k2" (at 544.83 160.02 90)
      (effects (font (size 1.27 1.27) (thickness 0.15)) (justify left))
    )
    (property "License" "Apache-2.0" (at 518.16 176.53 0)
      (effects (font (size 1.27 1.27) (thickness 0.15)) (justify left bottom) hide)
    )
    (property "Author" "Antmicro" (at 515.62 176.53 0)
      (effects (font (size 1.27 1.27) (thickness 0.15)) (justify left bottom) hide)
    )
    (property "Tolerance" "1%" (at 533.4 176.53 0)
      (effects (font (size 1.27 1.27)) (justify left bottom) hide)
    )
    (property "DNP" "DNP" (at 543.56 156.21 0)
      (effects (font (size 1.27 1.27)) hide)
    )
    (pin "1")
    (pin "2")
    (instances
      (project "sdi-mipi-bridge"
        (path ""
          (reference "R94") (unit 1)
        )
      )
    )
  )

  (symbol (lib_id "sdi-mipi-bridge:C_10n_0402") (at 156.21 152.4 0) (unit 1)
    (in_bom yes) (on_board yes) (dnp no) (fields_autoplaced)
    (property "Reference" "C65" (at 158.75 149.86 0)
      (effects (font (size 1.27 1.27)))
    )
    (property "Value" "C_10n_0402" (at 176.53 162.56 0)
      (effects (font (size 1.27 1.27) (thickness 0.15)) (justify left bottom) hide)
    )
    (property "Footprint" "sdi-mipi-bridge-footprints:C_0402_1005Metric" (at 176.53 165.1 0)
      (effects (font (size 1.27 1.27) (thickness 0.15)) (justify left bottom) hide)
    )
    (property "Datasheet" "https://search.murata.co.jp/Ceramy/image/img/A01X/G101/ENG/GRM155R71H103KA88-01.pdf" (at 176.53 167.64 0)
      (effects (font (size 1.27 1.27) (thickness 0.15)) (justify left bottom) hide)
    )
    (property "Manufacturer" "Murata" (at 176.53 172.72 0)
      (effects (font (size 1.27 1.27) (thickness 0.15)) (justify left bottom) hide)
    )
    (property "MPN" "GRM155R71H103KA88D" (at 176.53 170.18 0)
      (effects (font (size 1.27 1.27) (thickness 0.15)) (justify left bottom) hide)
    )
    (property "Val" "10n" (at 158.75 154.94 0)
      (effects (font (size 1.27 1.27) (thickness 0.15)))
    )
    (property "License" "Apache-2.0" (at 176.53 175.26 0)
      (effects (font (size 1.27 1.27) (thickness 0.15)) (justify left bottom) hide)
    )
    (property "Author" "Antmicro" (at 176.53 177.8 0)
      (effects (font (size 1.27 1.27) (thickness 0.15)) (justify left bottom) hide)
    )
    (property "Voltage" "50V" (at 176.53 180.34 0)
      (effects (font (size 1.27 1.27)) (justify left bottom) hide)
    )
    (property "Dielectric" "X7R" (at 176.53 182.88 0)
      (effects (font (size 1.27 1.27)) (justify left bottom) hide)
    )
    (pin "1")
    (pin "2")
    (instances
      (project "sdi-mipi-bridge"
        (path ""
          (reference "C65") (unit 1)
        )
      )
    )
  )

  (symbol (lib_id "sdi-mipi-bridge:GNDA") (at 162.56 153.67 0) (mirror y) (unit 1)
    (in_bom yes) (on_board yes) (dnp no)
    (property "Reference" "#PWR0103" (at 162.56 160.02 0)
      (effects (font (size 1.27 1.27)) hide)
    )
    (property "Value" "GNDA" (at 162.56 157.48 0)
      (effects (font (size 1.27 1.27)))
    )
    (property "Footprint" "" (at 162.56 153.67 0)
      (effects (font (size 1.27 1.27)) hide)
    )
    (property "Datasheet" "" (at 162.56 153.67 0)
      (effects (font (size 1.27 1.27)) hide)
    )
    (pin "1")
    (instances
      (project "sdi-mipi-bridge"
        (path ""
          (reference "#PWR0103") (unit 1)
        )
      )
    )
  )

  (symbol (lib_id "sdi-mipi-bridge:R_100R_0402") (at 346.71 251.46 0) (mirror y) (unit 1)
    (in_bom yes) (on_board yes) (dnp no)
    (property "Reference" "R64" (at 344.17 248.92 0)
      (effects (font (size 1.27 1.27)))
    )
    (property "Value" "R_100R_0402" (at 346.71 255.27 0)
      (effects (font (size 1.27 1.27) (thickness 0.15)) (justify left bottom) hide)
    )
    (property "Footprint" "sdi-mipi-bridge-footprints:R_0402_1005Metric" (at 341.63 246.38 0)
      (effects (font (size 1.27 1.27) (thickness 0.15)) (justify left bottom) hide)
    )
    (property "Datasheet" "https://www.bourns.com/docs/product-datasheets/cr.pdf" (at 346.71 251.46 0)
      (effects (font (size 1.27 1.27) (thickness 0.15)) (justify left bottom) hide)
    )
    (property "Manufacturer" "Bourns" (at 341.63 241.3 0)
      (effects (font (size 1.27 1.27) (thickness 0.15)) (justify left bottom) hide)
    )
    (property "MPN" "CR0402-FX-1000GLF" (at 341.63 243.84 0)
      (effects (font (size 1.27 1.27) (thickness 0.15)) (justify left bottom) hide)
    )
    (property "Val" "100R" (at 344.17 254 0)
      (effects (font (size 1.27 1.27) (thickness 0.15)))
    )
    (property "License" "Apache-2.0" (at 326.39 276.86 0)
      (effects (font (size 1.27 1.27) (thickness 0.15)) (justify left bottom) hide)
    )
    (property "Author" "Antmicro" (at 326.39 279.4 0)
      (effects (font (size 1.27 1.27) (thickness 0.15)) (justify left bottom) hide)
    )
    (property "Tolerance" "1%" (at 326.39 261.62 0)
      (effects (font (size 1.27 1.27)) (justify left bottom) hide)
    )
    (pin "1")
    (pin "2")
    (instances
      (project "sdi-mipi-bridge"
        (path ""
          (reference "R64") (unit 1)
        )
      )
    )
  )

  (symbol (lib_id "sdi-mipi-bridge:LED_G_0603_LG_L29K-G2J1-24-Z") (at 354.33 251.46 0) (mirror x) (unit 1)
    (in_bom yes) (on_board yes) (dnp no)
    (property "Reference" "D5" (at 358.14 248.92 0)
      (effects (font (size 1.27 1.27)))
    )
    (property "Value" "LED_G_0603_LG_L29K-G2J1-24-Z" (at 361.95 257.81 0)
      (effects (font (size 1.27 1.27) (thickness 0.15)) (justify left bottom) hide)
    )
    (property "Footprint" "sdi-mipi-bridge-footprints:LED_0603_1608Metric_G" (at 359.41 256.54 0)
      (effects (font (size 1.27 1.27) (thickness 0.15)) (justify left bottom) hide)
    )
    (property "Datasheet" "https://dammedia.osram.info/media/resource/hires/osram-dam-2493945/LG%20L29K.pdf" (at 359.41 259.08 0)
      (effects (font (size 1.27 1.27) (thickness 0.15)) (justify left bottom) hide)
    )
    (property "MPN" "LG L29K-G2J1-24-Z" (at 358.14 255.27 0)
      (effects (font (size 1.27 1.27) (thickness 0.15)))
    )
    (property "Manufacturer" "Osram" (at 359.41 279.4 0)
      (effects (font (size 1.27 1.27) (thickness 0.15)) (justify left bottom) hide)
    )
    (property "Author" "Antmicro" (at 377.19 231.14 0)
      (effects (font (size 1.27 1.27) (thickness 0.15)) (justify left bottom) hide)
    )
    (property "License" "Apache-2.0" (at 377.19 228.6 0)
      (effects (font (size 1.27 1.27) (thickness 0.15)) (justify left bottom) hide)
    )
    (pin "1")
    (pin "2")
    (instances
      (project "sdi-mipi-bridge"
        (path ""
          (reference "D5") (unit 1)
        )
      )
    )
  )

  (symbol (lib_id "sdi-mipi-bridge:C_10n_0402") (at 90.17 139.7 90) (unit 1)
    (in_bom yes) (on_board yes) (dnp no) (fields_autoplaced)
    (property "Reference" "C22" (at 92.71 135.8835 90)
      (effects (font (size 1.27 1.27)) (justify right))
    )
    (property "Value" "C_10n_0402" (at 100.33 119.38 0)
      (effects (font (size 1.27 1.27) (thickness 0.15)) (justify left bottom) hide)
    )
    (property "Footprint" "sdi-mipi-bridge-footprints:C_0402_1005Metric" (at 102.87 119.38 0)
      (effects (font (size 1.27 1.27) (thickness 0.15)) (justify left bottom) hide)
    )
    (property "Datasheet" "https://search.murata.co.jp/Ceramy/image/img/A01X/G101/ENG/GRM155R71H103KA88-01.pdf" (at 105.41 119.38 0)
      (effects (font (size 1.27 1.27) (thickness 0.15)) (justify left bottom) hide)
    )
    (property "Manufacturer" "Murata" (at 110.49 119.38 0)
      (effects (font (size 1.27 1.27) (thickness 0.15)) (justify left bottom) hide)
    )
    (property "MPN" "GRM155R71H103KA88D" (at 107.95 119.38 0)
      (effects (font (size 1.27 1.27) (thickness 0.15)) (justify left bottom) hide)
    )
    (property "Val" "10n" (at 92.71 138.4235 90)
      (effects (font (size 1.27 1.27) (thickness 0.15)) (justify right))
    )
    (property "License" "Apache-2.0" (at 113.03 119.38 0)
      (effects (font (size 1.27 1.27) (thickness 0.15)) (justify left bottom) hide)
    )
    (property "Author" "Antmicro" (at 115.57 119.38 0)
      (effects (font (size 1.27 1.27) (thickness 0.15)) (justify left bottom) hide)
    )
    (property "Voltage" "50V" (at 118.11 119.38 0)
      (effects (font (size 1.27 1.27)) (justify left bottom) hide)
    )
    (property "Dielectric" "X7R" (at 120.65 119.38 0)
      (effects (font (size 1.27 1.27)) (justify left bottom) hide)
    )
    (pin "1")
    (pin "2")
    (instances
      (project "sdi-mipi-bridge"
        (path ""
          (reference "C22") (unit 1)
        )
      )
    )
  )

  (symbol (lib_id "sdi-mipi-bridge:GNDA") (at 90.17 139.7 0) (unit 1)
    (in_bom yes) (on_board yes) (dnp no)
    (property "Reference" "#PWR024" (at 90.17 146.05 0)
      (effects (font (size 1.27 1.27)) hide)
    )
    (property "Value" "GNDA" (at 90.17 143.51 0)
      (effects (font (size 1.27 1.27)))
    )
    (property "Footprint" "" (at 90.17 139.7 0)
      (effects (font (size 1.27 1.27)) hide)
    )
    (property "Datasheet" "" (at 90.17 139.7 0)
      (effects (font (size 1.27 1.27)) hide)
    )
    (pin "1")
    (instances
      (project "sdi-mipi-bridge"
        (path ""
          (reference "#PWR024") (unit 1)
        )
      )
    )
  )

  (symbol (lib_id "sdi-mipi-bridge:+1V2") (at 228.6 295.91 0) (unit 1)
    (in_bom yes) (on_board yes) (dnp no)
    (property "Reference" "#PWR041" (at 228.6 299.72 0)
      (effects (font (size 1.27 1.27)) hide)
    )
    (property "Value" "+1V2" (at 228.981 291.5158 0)
      (effects (font (size 1.27 1.27)))
    )
    (property "Footprint" "" (at 228.6 295.91 0)
      (effects (font (size 1.27 1.27)) hide)
    )
    (property "Datasheet" "" (at 228.6 295.91 0)
      (effects (font (size 1.27 1.27)) hide)
    )
    (pin "1")
    (instances
      (project "sdi-mipi-bridge"
        (path ""
          (reference "#PWR041") (unit 1)
        )
      )
    )
  )

  (symbol (lib_id "sdi-mipi-bridge:antmicro_logo") (at 20.32 186.69 0) (unit 1)
    (in_bom yes) (on_board yes) (dnp no) (fields_autoplaced)
    (property "Reference" "N1" (at 26.67 184.3975 0)
      (effects (font (size 1.27 1.27)) (justify left))
    )
    (property "Value" "antmicro_logo" (at 26.67 186.9375 0)
      (effects (font (size 1.27 1.27) (thickness 0.15)) (justify left))
    )
    (property "Footprint" "sdi-mipi-bridge-footprints:antmicro-logo_scaled_20mm" (at 17.78 180.34 0)
      (effects (font (size 1.27 1.27) (thickness 0.15)) (justify left bottom) hide)
    )
    (property "Datasheet" "" (at 20.32 177.8 0)
      (effects (font (size 1.27 1.27) (thickness 0.15)) (justify left bottom) hide)
    )
    (property "MPN" "" (at 20.32 186.69 0)
      (effects (font (size 1.27 1.27)) hide)
    )
    (property "Manufacturer" "" (at 35.56 207.01 0)
      (effects (font (size 1.27 1.27) (thickness 0.15)) (justify left bottom) hide)
    )
    (property "Author" "Antmicro" (at 35.56 201.93 0)
      (effects (font (size 1.27 1.27) (thickness 0.15)) (justify left bottom) hide)
    )
    (property "License" "Apache-2.0" (at 35.56 204.47 0)
      (effects (font (size 1.27 1.27) (thickness 0.15)) (justify left bottom) hide)
    )
    (instances
      (project "sdi-mipi-bridge"
        (path ""
          (reference "N1") (unit 1)
        )
      )
    )
  )

  (symbol (lib_id "sdi-mipi-bridge:GNDA") (at 110.49 166.37 0) (mirror y) (unit 1)
    (in_bom yes) (on_board yes) (dnp no)
    (property "Reference" "#PWR015" (at 110.49 172.72 0)
      (effects (font (size 1.27 1.27)) hide)
    )
    (property "Value" "GNDA" (at 110.363 170.7642 0)
      (effects (font (size 1.27 1.27)))
    )
    (property "Footprint" "" (at 110.49 166.37 0)
      (effects (font (size 1.27 1.27)) hide)
    )
    (property "Datasheet" "" (at 110.49 166.37 0)
      (effects (font (size 1.27 1.27)) hide)
    )
    (pin "1")
    (instances
      (project "sdi-mipi-bridge"
        (path ""
          (reference "#PWR015") (unit 1)
        )
      )
    )
  )

  (symbol (lib_id "sdi-mipi-bridge:R_0R_0402") (at 439.42 151.13 0) (mirror y) (unit 1)
    (in_bom yes) (on_board yes) (dnp no)
    (property "Reference" "R92" (at 433.07 149.86 0)
      (effects (font (size 1.27 1.27)))
    )
    (property "Value" "R_0R_0402" (at 419.1 163.83 0)
      (effects (font (size 1.27 1.27) (thickness 0.15)) (justify left bottom) hide)
    )
    (property "Footprint" "sdi-mipi-bridge-footprints:R_0402_1005Metric" (at 419.1 166.37 0)
      (effects (font (size 1.27 1.27) (thickness 0.15)) (justify left bottom) hide)
    )
    (property "Datasheet" "https://industrial.panasonic.com/cdbs/www-data/pdf/RDA0000/AOA0000C301.pdf" (at 419.1 168.91 0)
      (effects (font (size 1.27 1.27) (thickness 0.15)) (justify left bottom) hide)
    )
    (property "Manufacturer" "Panasonic" (at 419.1 173.99 0)
      (effects (font (size 1.27 1.27) (thickness 0.15)) (justify left bottom) hide)
    )
    (property "MPN" "ERJ2GE0R00X" (at 419.1 171.45 0)
      (effects (font (size 1.27 1.27) (thickness 0.15)) (justify left bottom) hide)
    )
    (property "Val" "0R" (at 441.96 151.13 0)
      (effects (font (size 1.27 1.27) (thickness 0.15)) (justify left bottom))
    )
    (property "License" "Apache-2.0" (at 419.1 176.53 0)
      (effects (font (size 1.27 1.27) (thickness 0.15)) (justify left bottom) hide)
    )
    (property "Author" "Antmicro" (at 419.1 179.07 0)
      (effects (font (size 1.27 1.27) (thickness 0.15)) (justify left bottom) hide)
    )
    (property "Tolerance" "~" (at 419.1 161.29 0)
      (effects (font (size 1.27 1.27)) (justify left bottom) hide)
    )
    (property "Current" "1A" (at 419.1 181.61 0)
      (effects (font (size 1.27 1.27) (thickness 0.15)) (justify left bottom) hide)
    )
    (pin "1")
    (pin "2")
    (instances
      (project "sdi-mipi-bridge"
        (path ""
          (reference "R92") (unit 1)
        )
      )
    )
  )

  (symbol (lib_id "sdi-mipi-bridge:+1V2") (at 228.6 259.08 0) (unit 1)
    (in_bom yes) (on_board yes) (dnp no)
    (property "Reference" "#PWR039" (at 228.6 262.89 0)
      (effects (font (size 1.27 1.27)) hide)
    )
    (property "Value" "+1V2" (at 228.981 254.6858 0)
      (effects (font (size 1.27 1.27)))
    )
    (property "Footprint" "" (at 228.6 259.08 0)
      (effects (font (size 1.27 1.27)) hide)
    )
    (property "Datasheet" "" (at 228.6 259.08 0)
      (effects (font (size 1.27 1.27)) hide)
    )
    (pin "1")
    (instances
      (project "sdi-mipi-bridge"
        (path ""
          (reference "#PWR039") (unit 1)
        )
      )
    )
  )

  (symbol (lib_id "sdi-mipi-bridge:C_4u7_0402") (at 238.76 306.07 90) (unit 1)
    (in_bom yes) (on_board yes) (dnp no) (fields_autoplaced)
    (property "Reference" "C42" (at 241.3 302.2535 90)
      (effects (font (size 1.27 1.27)) (justify right))
    )
    (property "Value" "C_4u7_0402" (at 242.57 306.07 0)
      (effects (font (size 1.524 1.524)) hide)
    )
    (property "Footprint" "sdi-mipi-bridge-footprints:C_0402_1005Metric" (at 233.68 300.99 0)
      (effects (font (size 1.524 1.524)) (justify left) hide)
    )
    (property "Datasheet" " " (at 238.76 306.07 0)
      (effects (font (size 1.27 1.27)) hide)
    )
    (property "Manufacturer" "Murata" (at 228.6 300.99 0)
      (effects (font (size 1.524 1.524)) (justify left) hide)
    )
    (property "MPN" "GRM155R61A475MEAAD" (at 231.14 300.99 0)
      (effects (font (size 1.524 1.524)) (justify left) hide)
    )
    (property "Val" "4u7" (at 241.3 304.7935 90)
      (effects (font (size 1.27 1.27)) (justify right))
    )
    (property "License" "Apache-2.0" (at 261.62 285.75 0)
      (effects (font (size 1.27 1.27) (thickness 0.15)) (justify left bottom) hide)
    )
    (property "Author" "Antmicro" (at 264.16 285.75 0)
      (effects (font (size 1.27 1.27) (thickness 0.15)) (justify left bottom) hide)
    )
    (property "Voltage" "" (at 266.7 285.75 0)
      (effects (font (size 1.27 1.27)) (justify left bottom) hide)
    )
    (property "Dielectric" "" (at 269.24 285.75 0)
      (effects (font (size 1.27 1.27)) (justify left bottom) hide)
    )
    (pin "1")
    (pin "2")
    (instances
      (project "sdi-mipi-bridge"
        (path ""
          (reference "C42") (unit 1)
        )
      )
    )
  )

  (symbol (lib_id "sdi-mipi-bridge:R_0R_0402") (at 337.82 207.01 270) (unit 1)
    (in_bom yes) (on_board yes) (dnp no)
    (property "Reference" "R31" (at 339.09 208.28 90)
      (effects (font (size 1.27 1.27)) (justify left))
    )
    (property "Value" "R_0R_0402" (at 334.01 207.01 0)
      (effects (font (size 1.27 1.27) (thickness 0.15)) (justify left bottom) hide)
    )
    (property "Footprint" "sdi-mipi-bridge-footprints:R_0402_1005Metric" (at 342.9 212.09 0)
      (effects (font (size 1.27 1.27) (thickness 0.15)) (justify left bottom) hide)
    )
    (property "Datasheet" "https://industrial.panasonic.com/cdbs/www-data/pdf/RDA0000/AOA0000C301.pdf" (at 337.82 207.01 0)
      (effects (font (size 1.27 1.27) (thickness 0.15)) (justify left bottom) hide)
    )
    (property "Manufacturer" "Panasonic" (at 347.98 212.09 0)
      (effects (font (size 1.27 1.27) (thickness 0.15)) (justify left bottom) hide)
    )
    (property "MPN" "ERJ2GE0R00X" (at 345.44 212.09 0)
      (effects (font (size 1.27 1.27) (thickness 0.15)) (justify left bottom) hide)
    )
    (property "Val" "0R" (at 339.09 210.82 90)
      (effects (font (size 1.27 1.27) (thickness 0.15)) (justify left))
    )
    (property "License" "Apache-2.0" (at 312.42 227.33 0)
      (effects (font (size 1.27 1.27) (thickness 0.15)) (justify left bottom) hide)
    )
    (property "Author" "Antmicro" (at 309.88 227.33 0)
      (effects (font (size 1.27 1.27) (thickness 0.15)) (justify left bottom) hide)
    )
    (property "Tolerance" "~" (at 327.66 227.33 0)
      (effects (font (size 1.27 1.27)) (justify left bottom) hide)
    )
    (property "Current" "1A" (at 307.34 227.33 0)
      (effects (font (size 1.27 1.27) (thickness 0.15)) (justify left bottom) hide)
    )
    (pin "1")
    (pin "2")
    (instances
      (project "sdi-mipi-bridge"
        (path ""
          (reference "R31") (unit 1)
        )
      )
    )
  )

  (symbol (lib_id "sdi-mipi-bridge:R_0R_0402") (at 543.56 147.32 270) (unit 1)
    (in_bom yes) (on_board yes) (dnp no) (fields_autoplaced)
    (property "Reference" "R67" (at 546.1 148.5899 90)
      (effects (font (size 1.27 1.27)) (justify left))
    )
    (property "Value" "R_0R_0402" (at 530.86 167.64 0)
      (effects (font (size 1.27 1.27) (thickness 0.15)) (justify left bottom) hide)
    )
    (property "Footprint" "sdi-mipi-bridge-footprints:R_0402_1005Metric" (at 528.32 167.64 0)
      (effects (font (size 1.27 1.27) (thickness 0.15)) (justify left bottom) hide)
    )
    (property "Datasheet" "https://industrial.panasonic.com/cdbs/www-data/pdf/RDA0000/AOA0000C301.pdf" (at 525.78 167.64 0)
      (effects (font (size 1.27 1.27) (thickness 0.15)) (justify left bottom) hide)
    )
    (property "Manufacturer" "Panasonic" (at 520.7 167.64 0)
      (effects (font (size 1.27 1.27) (thickness 0.15)) (justify left bottom) hide)
    )
    (property "MPN" "ERJ2GE0R00X" (at 523.24 167.64 0)
      (effects (font (size 1.27 1.27) (thickness 0.15)) (justify left bottom) hide)
    )
    (property "Val" "0R" (at 546.1 151.1299 90)
      (effects (font (size 1.27 1.27) (thickness 0.15)) (justify left))
    )
    (property "License" "Apache-2.0" (at 518.16 167.64 0)
      (effects (font (size 1.27 1.27) (thickness 0.15)) (justify left bottom) hide)
    )
    (property "Author" "Antmicro" (at 515.62 167.64 0)
      (effects (font (size 1.27 1.27) (thickness 0.15)) (justify left bottom) hide)
    )
    (property "Tolerance" "~" (at 533.4 167.64 0)
      (effects (font (size 1.27 1.27)) (justify left bottom) hide)
    )
    (property "Current" "1A" (at 513.08 167.64 0)
      (effects (font (size 1.27 1.27) (thickness 0.15)) (justify left bottom) hide)
    )
    (pin "1")
    (pin "2")
    (instances
      (project "sdi-mipi-bridge"
        (path ""
          (reference "R67") (unit 1)
        )
      )
    )
  )

  (symbol (lib_id "sdi-mipi-bridge:GNDREF") (at 58.42 130.81 0) (unit 1)
    (in_bom yes) (on_board yes) (dnp no)
    (property "Reference" "#PWR070" (at 58.42 137.16 0)
      (effects (font (size 1.27 1.27)) hide)
    )
    (property "Value" "GNDREF" (at 58.547 135.2042 0)
      (effects (font (size 1.27 1.27)))
    )
    (property "Footprint" "" (at 58.42 130.81 0)
      (effects (font (size 1.27 1.27)) hide)
    )
    (property "Datasheet" "" (at 58.42 130.81 0)
      (effects (font (size 1.27 1.27)) hide)
    )
    (pin "1")
    (instances
      (project "sdi-mipi-bridge"
        (path ""
          (reference "#PWR070") (unit 1)
        )
      )
    )
  )

  (symbol (lib_id "sdi-mipi-bridge:C_100n_6V3_0402") (at 228.6 306.07 90) (unit 1)
    (in_bom yes) (on_board yes) (dnp no) (fields_autoplaced)
    (property "Reference" "C39" (at 231.14 302.2535 90)
      (effects (font (size 1.27 1.27)) (justify right))
    )
    (property "Value" "C_100n_6V3_0402" (at 232.41 306.07 0)
      (effects (font (size 1.524 1.524)) hide)
    )
    (property "Footprint" "sdi-mipi-bridge-footprints:C_0402_1005Metric" (at 223.52 300.99 0)
      (effects (font (size 1.524 1.524)) (justify left) hide)
    )
    (property "Datasheet" " " (at 228.6 306.07 0)
      (effects (font (size 1.27 1.27)) hide)
    )
    (property "Manufacturer" "Walsin" (at 218.44 300.99 0)
      (effects (font (size 1.524 1.524)) (justify left) hide)
    )
    (property "MPN" "0402X104K6R3CT" (at 220.98 300.99 0)
      (effects (font (size 1.524 1.524)) (justify left) hide)
    )
    (property "Val" "100n" (at 231.14 304.7935 90)
      (effects (font (size 1.27 1.27)) (justify right))
    )
    (property "License" "Apache-2.0" (at 251.46 285.75 0)
      (effects (font (size 1.27 1.27) (thickness 0.15)) (justify left bottom) hide)
    )
    (property "Author" "Antmicro" (at 254 285.75 0)
      (effects (font (size 1.27 1.27) (thickness 0.15)) (justify left bottom) hide)
    )
    (property "Voltage" "" (at 256.54 285.75 0)
      (effects (font (size 1.27 1.27)) (justify left bottom) hide)
    )
    (property "Dielectric" "" (at 259.08 285.75 0)
      (effects (font (size 1.27 1.27)) (justify left bottom) hide)
    )
    (pin "1")
    (pin "2")
    (instances
      (project "sdi-mipi-bridge"
        (path ""
          (reference "C39") (unit 1)
        )
      )
    )
  )

  (symbol (lib_id "sdi-mipi-bridge:C_4u7_0402") (at 260.35 306.07 90) (unit 1)
    (in_bom yes) (on_board yes) (dnp no) (fields_autoplaced)
    (property "Reference" "C52" (at 262.89 302.2535 90)
      (effects (font (size 1.27 1.27)) (justify right))
    )
    (property "Value" "C_4u7_0402" (at 264.16 306.07 0)
      (effects (font (size 1.524 1.524)) hide)
    )
    (property "Footprint" "sdi-mipi-bridge-footprints:C_0402_1005Metric" (at 255.27 300.99 0)
      (effects (font (size 1.524 1.524)) (justify left) hide)
    )
    (property "Datasheet" " " (at 260.35 306.07 0)
      (effects (font (size 1.27 1.27)) hide)
    )
    (property "Manufacturer" "Murata" (at 250.19 300.99 0)
      (effects (font (size 1.524 1.524)) (justify left) hide)
    )
    (property "MPN" "GRM155R61A475MEAAD" (at 252.73 300.99 0)
      (effects (font (size 1.524 1.524)) (justify left) hide)
    )
    (property "Val" "4u7" (at 262.89 304.7935 90)
      (effects (font (size 1.27 1.27)) (justify right))
    )
    (property "License" "Apache-2.0" (at 283.21 285.75 0)
      (effects (font (size 1.27 1.27) (thickness 0.15)) (justify left bottom) hide)
    )
    (property "Author" "Antmicro" (at 285.75 285.75 0)
      (effects (font (size 1.27 1.27) (thickness 0.15)) (justify left bottom) hide)
    )
    (property "Voltage" "" (at 288.29 285.75 0)
      (effects (font (size 1.27 1.27)) (justify left bottom) hide)
    )
    (property "Dielectric" "" (at 290.83 285.75 0)
      (effects (font (size 1.27 1.27)) (justify left bottom) hide)
    )
    (pin "1")
    (pin "2")
    (instances
      (project "sdi-mipi-bridge"
        (path ""
          (reference "C52") (unit 1)
        )
      )
    )
  )

  (symbol (lib_id "sdi-mipi-bridge:C_100n_6V3_0402") (at 250.19 306.07 90) (unit 1)
    (in_bom yes) (on_board yes) (dnp no) (fields_autoplaced)
    (property "Reference" "C48" (at 252.73 302.2535 90)
      (effects (font (size 1.27 1.27)) (justify right))
    )
    (property "Value" "C_100n_6V3_0402" (at 254 306.07 0)
      (effects (font (size 1.524 1.524)) hide)
    )
    (property "Footprint" "sdi-mipi-bridge-footprints:C_0402_1005Metric" (at 245.11 300.99 0)
      (effects (font (size 1.524 1.524)) (justify left) hide)
    )
    (property "Datasheet" " " (at 250.19 306.07 0)
      (effects (font (size 1.27 1.27)) hide)
    )
    (property "Manufacturer" "Walsin" (at 240.03 300.99 0)
      (effects (font (size 1.524 1.524)) (justify left) hide)
    )
    (property "MPN" "0402X104K6R3CT" (at 242.57 300.99 0)
      (effects (font (size 1.524 1.524)) (justify left) hide)
    )
    (property "Val" "100n" (at 252.73 304.7935 90)
      (effects (font (size 1.27 1.27)) (justify right))
    )
    (property "License" "Apache-2.0" (at 273.05 285.75 0)
      (effects (font (size 1.27 1.27) (thickness 0.15)) (justify left bottom) hide)
    )
    (property "Author" "Antmicro" (at 275.59 285.75 0)
      (effects (font (size 1.27 1.27) (thickness 0.15)) (justify left bottom) hide)
    )
    (property "Voltage" "" (at 278.13 285.75 0)
      (effects (font (size 1.27 1.27)) (justify left bottom) hide)
    )
    (property "Dielectric" "" (at 280.67 285.75 0)
      (effects (font (size 1.27 1.27)) (justify left bottom) hide)
    )
    (pin "1")
    (pin "2")
    (instances
      (project "sdi-mipi-bridge"
        (path ""
          (reference "C48") (unit 1)
        )
      )
    )
  )

  (symbol (lib_id "sdi-mipi-bridge:+1V2") (at 528.32 237.49 0) (unit 1)
    (in_bom yes) (on_board yes) (dnp no)
    (property "Reference" "#PWR065" (at 528.32 241.3 0)
      (effects (font (size 1.27 1.27)) hide)
    )
    (property "Value" "+1V2" (at 528.701 233.0958 0)
      (effects (font (size 1.27 1.27)))
    )
    (property "Footprint" "" (at 528.32 237.49 0)
      (effects (font (size 1.27 1.27)) hide)
    )
    (property "Datasheet" "" (at 528.32 237.49 0)
      (effects (font (size 1.27 1.27)) hide)
    )
    (pin "1")
    (instances
      (project "sdi-mipi-bridge"
        (path ""
          (reference "#PWR065") (unit 1)
        )
      )
    )
  )

  (symbol (lib_id "sdi-mipi-bridge:GNDREF") (at 43.18 165.1 0) (unit 1)
    (in_bom yes) (on_board yes) (dnp no)
    (property "Reference" "#PWR073" (at 43.18 171.45 0)
      (effects (font (size 1.27 1.27)) hide)
    )
    (property "Value" "GNDREF" (at 43.307 169.4942 0)
      (effects (font (size 1.27 1.27)))
    )
    (property "Footprint" "" (at 43.18 165.1 0)
      (effects (font (size 1.27 1.27)) hide)
    )
    (property "Datasheet" "" (at 43.18 165.1 0)
      (effects (font (size 1.27 1.27)) hide)
    )
    (pin "1")
    (instances
      (project "sdi-mipi-bridge"
        (path ""
          (reference "#PWR073") (unit 1)
        )
      )
    )
  )

  (symbol (lib_id "sdi-mipi-bridge:GNDREF") (at 228.6 306.07 0) (unit 1)
    (in_bom yes) (on_board yes) (dnp no)
    (property "Reference" "#PWR045" (at 228.6 312.42 0)
      (effects (font (size 1.27 1.27)) hide)
    )
    (property "Value" "GNDREF" (at 228.727 310.4642 0)
      (effects (font (size 1.27 1.27)))
    )
    (property "Footprint" "" (at 228.6 306.07 0)
      (effects (font (size 1.27 1.27)) hide)
    )
    (property "Datasheet" "" (at 228.6 306.07 0)
      (effects (font (size 1.27 1.27)) hide)
    )
    (pin "1")
    (instances
      (project "sdi-mipi-bridge"
        (path ""
          (reference "#PWR045") (unit 1)
        )
      )
    )
  )

  (symbol (lib_id "sdi-mipi-bridge:C_100n_6V3_0402") (at 237.49 233.68 90) (unit 1)
    (in_bom yes) (on_board yes) (dnp no) (fields_autoplaced)
    (property "Reference" "C41" (at 240.03 229.8635 90)
      (effects (font (size 1.27 1.27)) (justify right))
    )
    (property "Value" "C_100n_6V3_0402" (at 241.3 233.68 0)
      (effects (font (size 1.524 1.524)) hide)
    )
    (property "Footprint" "sdi-mipi-bridge-footprints:C_0402_1005Metric" (at 232.41 228.6 0)
      (effects (font (size 1.524 1.524)) (justify left) hide)
    )
    (property "Datasheet" " " (at 237.49 233.68 0)
      (effects (font (size 1.27 1.27)) hide)
    )
    (property "Manufacturer" "Walsin" (at 227.33 228.6 0)
      (effects (font (size 1.524 1.524)) (justify left) hide)
    )
    (property "MPN" "0402X104K6R3CT" (at 229.87 228.6 0)
      (effects (font (size 1.524 1.524)) (justify left) hide)
    )
    (property "Val" "100n" (at 240.03 232.4035 90)
      (effects (font (size 1.27 1.27)) (justify right))
    )
    (property "License" "Apache-2.0" (at 260.35 213.36 0)
      (effects (font (size 1.27 1.27) (thickness 0.15)) (justify left bottom) hide)
    )
    (property "Author" "Antmicro" (at 262.89 213.36 0)
      (effects (font (size 1.27 1.27) (thickness 0.15)) (justify left bottom) hide)
    )
    (property "Voltage" "" (at 265.43 213.36 0)
      (effects (font (size 1.27 1.27)) (justify left bottom) hide)
    )
    (property "Dielectric" "" (at 267.97 213.36 0)
      (effects (font (size 1.27 1.27)) (justify left bottom) hide)
    )
    (pin "1")
    (pin "2")
    (instances
      (project "sdi-mipi-bridge"
        (path ""
          (reference "C41") (unit 1)
        )
      )
    )
  )

  (symbol (lib_id "sdi-mipi-bridge:C_100n_6V3_0402") (at 246.38 233.68 90) (unit 1)
    (in_bom yes) (on_board yes) (dnp no) (fields_autoplaced)
    (property "Reference" "C46" (at 248.92 229.8635 90)
      (effects (font (size 1.27 1.27)) (justify right))
    )
    (property "Value" "C_100n_6V3_0402" (at 250.19 233.68 0)
      (effects (font (size 1.524 1.524)) hide)
    )
    (property "Footprint" "sdi-mipi-bridge-footprints:C_0402_1005Metric" (at 241.3 228.6 0)
      (effects (font (size 1.524 1.524)) (justify left) hide)
    )
    (property "Datasheet" " " (at 246.38 233.68 0)
      (effects (font (size 1.27 1.27)) hide)
    )
    (property "Manufacturer" "Walsin" (at 236.22 228.6 0)
      (effects (font (size 1.524 1.524)) (justify left) hide)
    )
    (property "MPN" "0402X104K6R3CT" (at 238.76 228.6 0)
      (effects (font (size 1.524 1.524)) (justify left) hide)
    )
    (property "Val" "100n" (at 248.92 232.4035 90)
      (effects (font (size 1.27 1.27)) (justify right))
    )
    (property "License" "Apache-2.0" (at 269.24 213.36 0)
      (effects (font (size 1.27 1.27) (thickness 0.15)) (justify left bottom) hide)
    )
    (property "Author" "Antmicro" (at 271.78 213.36 0)
      (effects (font (size 1.27 1.27) (thickness 0.15)) (justify left bottom) hide)
    )
    (property "Voltage" "" (at 274.32 213.36 0)
      (effects (font (size 1.27 1.27)) (justify left bottom) hide)
    )
    (property "Dielectric" "" (at 276.86 213.36 0)
      (effects (font (size 1.27 1.27)) (justify left bottom) hide)
    )
    (pin "1")
    (pin "2")
    (instances
      (project "sdi-mipi-bridge"
        (path ""
          (reference "C46") (unit 1)
        )
      )
    )
  )

  (symbol (lib_id "sdi-mipi-bridge:C_100n_6V3_0402") (at 256.54 233.68 90) (unit 1)
    (in_bom yes) (on_board yes) (dnp no) (fields_autoplaced)
    (property "Reference" "C50" (at 259.08 229.8635 90)
      (effects (font (size 1.27 1.27)) (justify right))
    )
    (property "Value" "C_100n_6V3_0402" (at 260.35 233.68 0)
      (effects (font (size 1.524 1.524)) hide)
    )
    (property "Footprint" "sdi-mipi-bridge-footprints:C_0402_1005Metric" (at 251.46 228.6 0)
      (effects (font (size 1.524 1.524)) (justify left) hide)
    )
    (property "Datasheet" " " (at 256.54 233.68 0)
      (effects (font (size 1.27 1.27)) hide)
    )
    (property "Manufacturer" "Walsin" (at 246.38 228.6 0)
      (effects (font (size 1.524 1.524)) (justify left) hide)
    )
    (property "MPN" "0402X104K6R3CT" (at 248.92 228.6 0)
      (effects (font (size 1.524 1.524)) (justify left) hide)
    )
    (property "Val" "100n" (at 259.08 232.4035 90)
      (effects (font (size 1.27 1.27)) (justify right))
    )
    (property "License" "Apache-2.0" (at 279.4 213.36 0)
      (effects (font (size 1.27 1.27) (thickness 0.15)) (justify left bottom) hide)
    )
    (property "Author" "Antmicro" (at 281.94 213.36 0)
      (effects (font (size 1.27 1.27) (thickness 0.15)) (justify left bottom) hide)
    )
    (property "Voltage" "" (at 284.48 213.36 0)
      (effects (font (size 1.27 1.27)) (justify left bottom) hide)
    )
    (property "Dielectric" "" (at 287.02 213.36 0)
      (effects (font (size 1.27 1.27)) (justify left bottom) hide)
    )
    (pin "1")
    (pin "2")
    (instances
      (project "sdi-mipi-bridge"
        (path ""
          (reference "C50") (unit 1)
        )
      )
    )
  )

  (symbol (lib_id "sdi-mipi-bridge:C_100n_6V3_0402") (at 265.43 233.68 90) (unit 1)
    (in_bom yes) (on_board yes) (dnp no) (fields_autoplaced)
    (property "Reference" "C54" (at 267.97 229.8635 90)
      (effects (font (size 1.27 1.27)) (justify right))
    )
    (property "Value" "C_100n_6V3_0402" (at 269.24 233.68 0)
      (effects (font (size 1.524 1.524)) hide)
    )
    (property "Footprint" "sdi-mipi-bridge-footprints:C_0402_1005Metric" (at 260.35 228.6 0)
      (effects (font (size 1.524 1.524)) (justify left) hide)
    )
    (property "Datasheet" " " (at 265.43 233.68 0)
      (effects (font (size 1.27 1.27)) hide)
    )
    (property "Manufacturer" "Walsin" (at 255.27 228.6 0)
      (effects (font (size 1.524 1.524)) (justify left) hide)
    )
    (property "MPN" "0402X104K6R3CT" (at 257.81 228.6 0)
      (effects (font (size 1.524 1.524)) (justify left) hide)
    )
    (property "Val" "100n" (at 267.97 232.4035 90)
      (effects (font (size 1.27 1.27)) (justify right))
    )
    (property "License" "Apache-2.0" (at 288.29 213.36 0)
      (effects (font (size 1.27 1.27) (thickness 0.15)) (justify left bottom) hide)
    )
    (property "Author" "Antmicro" (at 290.83 213.36 0)
      (effects (font (size 1.27 1.27) (thickness 0.15)) (justify left bottom) hide)
    )
    (property "Voltage" "" (at 293.37 213.36 0)
      (effects (font (size 1.27 1.27)) (justify left bottom) hide)
    )
    (property "Dielectric" "" (at 295.91 213.36 0)
      (effects (font (size 1.27 1.27)) (justify left bottom) hide)
    )
    (pin "1")
    (pin "2")
    (instances
      (project "sdi-mipi-bridge"
        (path ""
          (reference "C54") (unit 1)
        )
      )
    )
  )

  (symbol (lib_id "sdi-mipi-bridge:C_100n_6V3_0402") (at 274.32 233.68 90) (unit 1)
    (in_bom yes) (on_board yes) (dnp no) (fields_autoplaced)
    (property "Reference" "C57" (at 276.86 229.8635 90)
      (effects (font (size 1.27 1.27)) (justify right))
    )
    (property "Value" "C_100n_6V3_0402" (at 278.13 233.68 0)
      (effects (font (size 1.524 1.524)) hide)
    )
    (property "Footprint" "sdi-mipi-bridge-footprints:C_0402_1005Metric" (at 269.24 228.6 0)
      (effects (font (size 1.524 1.524)) (justify left) hide)
    )
    (property "Datasheet" " " (at 274.32 233.68 0)
      (effects (font (size 1.27 1.27)) hide)
    )
    (property "Manufacturer" "Walsin" (at 264.16 228.6 0)
      (effects (font (size 1.524 1.524)) (justify left) hide)
    )
    (property "MPN" "0402X104K6R3CT" (at 266.7 228.6 0)
      (effects (font (size 1.524 1.524)) (justify left) hide)
    )
    (property "Val" "100n" (at 276.86 232.4035 90)
      (effects (font (size 1.27 1.27)) (justify right))
    )
    (property "License" "Apache-2.0" (at 297.18 213.36 0)
      (effects (font (size 1.27 1.27) (thickness 0.15)) (justify left bottom) hide)
    )
    (property "Author" "Antmicro" (at 299.72 213.36 0)
      (effects (font (size 1.27 1.27) (thickness 0.15)) (justify left bottom) hide)
    )
    (property "Voltage" "" (at 302.26 213.36 0)
      (effects (font (size 1.27 1.27)) (justify left bottom) hide)
    )
    (property "Dielectric" "" (at 304.8 213.36 0)
      (effects (font (size 1.27 1.27)) (justify left bottom) hide)
    )
    (pin "1")
    (pin "2")
    (instances
      (project "sdi-mipi-bridge"
        (path ""
          (reference "C57") (unit 1)
        )
      )
    )
  )

  (symbol (lib_id "sdi-mipi-bridge:R_0R_0402") (at 439.42 125.73 0) (mirror y) (unit 1)
    (in_bom yes) (on_board yes) (dnp no)
    (property "Reference" "R37" (at 433.07 124.46 0)
      (effects (font (size 1.27 1.27)))
    )
    (property "Value" "R_0R_0402" (at 419.1 138.43 0)
      (effects (font (size 1.27 1.27) (thickness 0.15)) (justify left bottom) hide)
    )
    (property "Footprint" "sdi-mipi-bridge-footprints:R_0402_1005Metric" (at 419.1 140.97 0)
      (effects (font (size 1.27 1.27) (thickness 0.15)) (justify left bottom) hide)
    )
    (property "Datasheet" "https://industrial.panasonic.com/cdbs/www-data/pdf/RDA0000/AOA0000C301.pdf" (at 419.1 143.51 0)
      (effects (font (size 1.27 1.27) (thickness 0.15)) (justify left bottom) hide)
    )
    (property "Manufacturer" "Panasonic" (at 419.1 148.59 0)
      (effects (font (size 1.27 1.27) (thickness 0.15)) (justify left bottom) hide)
    )
    (property "MPN" "ERJ2GE0R00X" (at 419.1 146.05 0)
      (effects (font (size 1.27 1.27) (thickness 0.15)) (justify left bottom) hide)
    )
    (property "Val" "0R" (at 441.96 125.73 0)
      (effects (font (size 1.27 1.27) (thickness 0.15)) (justify left bottom))
    )
    (property "License" "Apache-2.0" (at 419.1 151.13 0)
      (effects (font (size 1.27 1.27) (thickness 0.15)) (justify left bottom) hide)
    )
    (property "Author" "Antmicro" (at 419.1 153.67 0)
      (effects (font (size 1.27 1.27) (thickness 0.15)) (justify left bottom) hide)
    )
    (property "Tolerance" "~" (at 419.1 135.89 0)
      (effects (font (size 1.27 1.27)) (justify left bottom) hide)
    )
    (property "Current" "1A" (at 419.1 156.21 0)
      (effects (font (size 1.27 1.27) (thickness 0.15)) (justify left bottom) hide)
    )
    (pin "1")
    (pin "2")
    (instances
      (project "sdi-mipi-bridge"
        (path ""
          (reference "R37") (unit 1)
        )
      )
    )
  )

  (symbol (lib_id "sdi-mipi-bridge:R_0R_0402") (at 439.42 128.27 0) (mirror y) (unit 1)
    (in_bom yes) (on_board yes) (dnp no)
    (property "Reference" "R38" (at 433.07 127 0)
      (effects (font (size 1.27 1.27)))
    )
    (property "Value" "R_0R_0402" (at 419.1 140.97 0)
      (effects (font (size 1.27 1.27) (thickness 0.15)) (justify left bottom) hide)
    )
    (property "Footprint" "sdi-mipi-bridge-footprints:R_0402_1005Metric" (at 419.1 143.51 0)
      (effects (font (size 1.27 1.27) (thickness 0.15)) (justify left bottom) hide)
    )
    (property "Datasheet" "https://industrial.panasonic.com/cdbs/www-data/pdf/RDA0000/AOA0000C301.pdf" (at 419.1 146.05 0)
      (effects (font (size 1.27 1.27) (thickness 0.15)) (justify left bottom) hide)
    )
    (property "Manufacturer" "Panasonic" (at 419.1 151.13 0)
      (effects (font (size 1.27 1.27) (thickness 0.15)) (justify left bottom) hide)
    )
    (property "MPN" "ERJ2GE0R00X" (at 419.1 148.59 0)
      (effects (font (size 1.27 1.27) (thickness 0.15)) (justify left bottom) hide)
    )
    (property "Val" "0R" (at 441.96 128.27 0)
      (effects (font (size 1.27 1.27) (thickness 0.15)) (justify left bottom))
    )
    (property "License" "Apache-2.0" (at 419.1 153.67 0)
      (effects (font (size 1.27 1.27) (thickness 0.15)) (justify left bottom) hide)
    )
    (property "Author" "Antmicro" (at 419.1 156.21 0)
      (effects (font (size 1.27 1.27) (thickness 0.15)) (justify left bottom) hide)
    )
    (property "Tolerance" "~" (at 419.1 138.43 0)
      (effects (font (size 1.27 1.27)) (justify left bottom) hide)
    )
    (property "Current" "1A" (at 419.1 158.75 0)
      (effects (font (size 1.27 1.27) (thickness 0.15)) (justify left bottom) hide)
    )
    (pin "1")
    (pin "2")
    (instances
      (project "sdi-mipi-bridge"
        (path ""
          (reference "R38") (unit 1)
        )
      )
    )
  )

  (symbol (lib_id "sdi-mipi-bridge:FB_120Z_2A_0603") (at 228.6 260.35 270) (unit 1)
    (in_bom yes) (on_board yes) (dnp no) (fields_autoplaced)
    (property "Reference" "FB2" (at 232.41 259.08 90)
      (effects (font (size 1.27 1.27)) (justify left))
    )
    (property "Value" "BLM18PG121SH1D" (at 232.41 262.89 90)
      (effects (font (size 1.524 1.524)) (justify left))
    )
    (property "Footprint" "sdi-mipi-bridge-footprints:FB_0603_1608Metric" (at 233.68 265.43 0)
      (effects (font (size 1.524 1.524)) (justify left) hide)
    )
    (property "Datasheet" "https://www.murata.com/en-us/products/productdata/8796738650142/ENFA0003.pdf" (at 236.22 265.43 0)
      (effects (font (size 1.524 1.524)) (justify left) hide)
    )
    (property "MPN" "BLM18PG121SN1D" (at 241.3 265.43 0)
      (effects (font (size 1.524 1.524)) (justify left) hide)
    )
    (property "Manufacturer" "Murata" (at 256.54 265.43 0)
      (effects (font (size 1.524 1.524)) (justify left) hide)
    )
    (property "Author" "Antmicro" (at 210.82 275.59 0)
      (effects (font (size 1.27 1.27) (thickness 0.15)) (justify left bottom) hide)
    )
    (property "License" "Apache-2.0" (at 208.28 275.59 0)
      (effects (font (size 1.27 1.27) (thickness 0.15)) (justify left bottom) hide)
    )
    (pin "1")
    (pin "2")
    (instances
      (project "sdi-mipi-bridge"
        (path ""
          (reference "FB2") (unit 1)
        )
      )
    )
  )

  (symbol (lib_id "sdi-mipi-bridge:C_2u2_0402") (at 228.6 273.05 90) (unit 1)
    (in_bom yes) (on_board yes) (dnp no) (fields_autoplaced)
    (property "Reference" "C38" (at 231.14 269.2335 90)
      (effects (font (size 1.27 1.27)) (justify right))
    )
    (property "Value" "C_2u2_0402" (at 232.41 273.05 0)
      (effects (font (size 1.524 1.524)) hide)
    )
    (property "Footprint" "sdi-mipi-bridge-footprints:C_0402_1005Metric" (at 223.52 267.97 0)
      (effects (font (size 1.524 1.524)) (justify left) hide)
    )
    (property "Datasheet" " " (at 228.6 273.05 0)
      (effects (font (size 1.27 1.27)) hide)
    )
    (property "Manufacturer" "TDK" (at 218.44 267.97 0)
      (effects (font (size 1.524 1.524)) (justify left) hide)
    )
    (property "MPN" "C1005X5R1A225K050BC" (at 220.98 267.97 0)
      (effects (font (size 1.524 1.524)) (justify left) hide)
    )
    (property "Val" "2u2" (at 231.14 271.7735 90)
      (effects (font (size 1.27 1.27)) (justify right))
    )
    (property "License" "Apache-2.0" (at 251.46 252.73 0)
      (effects (font (size 1.27 1.27) (thickness 0.15)) (justify left bottom) hide)
    )
    (property "Author" "Antmicro" (at 254 252.73 0)
      (effects (font (size 1.27 1.27) (thickness 0.15)) (justify left bottom) hide)
    )
    (property "Voltage" "" (at 256.54 252.73 0)
      (effects (font (size 1.27 1.27)) (justify left bottom) hide)
    )
    (property "Dielectric" "" (at 259.08 252.73 0)
      (effects (font (size 1.27 1.27)) (justify left bottom) hide)
    )
    (pin "1")
    (pin "2")
    (instances
      (project "sdi-mipi-bridge"
        (path ""
          (reference "C38") (unit 1)
        )
      )
    )
  )

  (symbol (lib_id "sdi-mipi-bridge:C_100n_6V3_0402") (at 237.49 273.05 90) (unit 1)
    (in_bom yes) (on_board yes) (dnp no) (fields_autoplaced)
    (property "Reference" "C40" (at 240.03 269.2335 90)
      (effects (font (size 1.27 1.27)) (justify right))
    )
    (property "Value" "C_100n_6V3_0402" (at 241.3 273.05 0)
      (effects (font (size 1.524 1.524)) hide)
    )
    (property "Footprint" "sdi-mipi-bridge-footprints:C_0402_1005Metric" (at 232.41 267.97 0)
      (effects (font (size 1.524 1.524)) (justify left) hide)
    )
    (property "Datasheet" " " (at 237.49 273.05 0)
      (effects (font (size 1.27 1.27)) hide)
    )
    (property "Manufacturer" "Walsin" (at 227.33 267.97 0)
      (effects (font (size 1.524 1.524)) (justify left) hide)
    )
    (property "MPN" "0402X104K6R3CT" (at 229.87 267.97 0)
      (effects (font (size 1.524 1.524)) (justify left) hide)
    )
    (property "Val" "100n" (at 240.03 271.7735 90)
      (effects (font (size 1.27 1.27)) (justify right))
    )
    (property "License" "Apache-2.0" (at 260.35 252.73 0)
      (effects (font (size 1.27 1.27) (thickness 0.15)) (justify left bottom) hide)
    )
    (property "Author" "Antmicro" (at 262.89 252.73 0)
      (effects (font (size 1.27 1.27) (thickness 0.15)) (justify left bottom) hide)
    )
    (property "Voltage" "" (at 265.43 252.73 0)
      (effects (font (size 1.27 1.27)) (justify left bottom) hide)
    )
    (property "Dielectric" "" (at 267.97 252.73 0)
      (effects (font (size 1.27 1.27)) (justify left bottom) hide)
    )
    (pin "1")
    (pin "2")
    (instances
      (project "sdi-mipi-bridge"
        (path ""
          (reference "C40") (unit 1)
        )
      )
    )
  )

  (symbol (lib_id "sdi-mipi-bridge:GNDREF") (at 237.49 274.32 0) (unit 1)
    (in_bom yes) (on_board yes) (dnp no)
    (property "Reference" "#PWR044" (at 237.49 280.67 0)
      (effects (font (size 1.27 1.27)) hide)
    )
    (property "Value" "GNDREF" (at 237.617 278.7142 0)
      (effects (font (size 1.27 1.27)))
    )
    (property "Footprint" "" (at 237.49 274.32 0)
      (effects (font (size 1.27 1.27)) hide)
    )
    (property "Datasheet" "" (at 237.49 274.32 0)
      (effects (font (size 1.27 1.27)) hide)
    )
    (pin "1")
    (instances
      (project "sdi-mipi-bridge"
        (path ""
          (reference "#PWR044") (unit 1)
        )
      )
    )
  )

  (symbol (lib_id "sdi-mipi-bridge:C_100n_6V3_0402") (at 246.38 273.05 90) (unit 1)
    (in_bom yes) (on_board yes) (dnp no) (fields_autoplaced)
    (property "Reference" "C44" (at 248.92 269.2335 90)
      (effects (font (size 1.27 1.27)) (justify right))
    )
    (property "Value" "C_100n_6V3_0402" (at 250.19 273.05 0)
      (effects (font (size 1.524 1.524)) hide)
    )
    (property "Footprint" "sdi-mipi-bridge-footprints:C_0402_1005Metric" (at 241.3 267.97 0)
      (effects (font (size 1.524 1.524)) (justify left) hide)
    )
    (property "Datasheet" " " (at 246.38 273.05 0)
      (effects (font (size 1.27 1.27)) hide)
    )
    (property "Manufacturer" "Walsin" (at 236.22 267.97 0)
      (effects (font (size 1.524 1.524)) (justify left) hide)
    )
    (property "MPN" "0402X104K6R3CT" (at 238.76 267.97 0)
      (effects (font (size 1.524 1.524)) (justify left) hide)
    )
    (property "Val" "100n" (at 248.92 271.7735 90)
      (effects (font (size 1.27 1.27)) (justify right))
    )
    (property "License" "Apache-2.0" (at 269.24 252.73 0)
      (effects (font (size 1.27 1.27) (thickness 0.15)) (justify left bottom) hide)
    )
    (property "Author" "Antmicro" (at 271.78 252.73 0)
      (effects (font (size 1.27 1.27) (thickness 0.15)) (justify left bottom) hide)
    )
    (property "Voltage" "" (at 274.32 252.73 0)
      (effects (font (size 1.27 1.27)) (justify left bottom) hide)
    )
    (property "Dielectric" "" (at 276.86 252.73 0)
      (effects (font (size 1.27 1.27)) (justify left bottom) hide)
    )
    (pin "1")
    (pin "2")
    (instances
      (project "sdi-mipi-bridge"
        (path ""
          (reference "C44") (unit 1)
        )
      )
    )
  )

  (symbol (lib_id "sdi-mipi-bridge:GNDREF") (at 246.38 274.32 0) (unit 1)
    (in_bom yes) (on_board yes) (dnp no)
    (property "Reference" "#PWR046" (at 246.38 280.67 0)
      (effects (font (size 1.27 1.27)) hide)
    )
    (property "Value" "GNDREF" (at 246.507 278.7142 0)
      (effects (font (size 1.27 1.27)))
    )
    (property "Footprint" "" (at 246.38 274.32 0)
      (effects (font (size 1.27 1.27)) hide)
    )
    (property "Datasheet" "" (at 246.38 274.32 0)
      (effects (font (size 1.27 1.27)) hide)
    )
    (pin "1")
    (instances
      (project "sdi-mipi-bridge"
        (path ""
          (reference "#PWR046") (unit 1)
        )
      )
    )
  )

  (symbol (lib_id "sdi-mipi-bridge:C_100n_6V3_0402") (at 256.54 273.05 90) (unit 1)
    (in_bom yes) (on_board yes) (dnp no) (fields_autoplaced)
    (property "Reference" "C49" (at 259.08 269.2335 90)
      (effects (font (size 1.27 1.27)) (justify right))
    )
    (property "Value" "C_100n_6V3_0402" (at 260.35 273.05 0)
      (effects (font (size 1.524 1.524)) hide)
    )
    (property "Footprint" "sdi-mipi-bridge-footprints:C_0402_1005Metric" (at 251.46 267.97 0)
      (effects (font (size 1.524 1.524)) (justify left) hide)
    )
    (property "Datasheet" " " (at 256.54 273.05 0)
      (effects (font (size 1.27 1.27)) hide)
    )
    (property "Manufacturer" "Walsin" (at 246.38 267.97 0)
      (effects (font (size 1.524 1.524)) (justify left) hide)
    )
    (property "MPN" "0402X104K6R3CT" (at 248.92 267.97 0)
      (effects (font (size 1.524 1.524)) (justify left) hide)
    )
    (property "Val" "100n" (at 259.08 271.7735 90)
      (effects (font (size 1.27 1.27)) (justify right))
    )
    (property "License" "Apache-2.0" (at 279.4 252.73 0)
      (effects (font (size 1.27 1.27) (thickness 0.15)) (justify left bottom) hide)
    )
    (property "Author" "Antmicro" (at 281.94 252.73 0)
      (effects (font (size 1.27 1.27) (thickness 0.15)) (justify left bottom) hide)
    )
    (property "Voltage" "" (at 284.48 252.73 0)
      (effects (font (size 1.27 1.27)) (justify left bottom) hide)
    )
    (property "Dielectric" "" (at 287.02 252.73 0)
      (effects (font (size 1.27 1.27)) (justify left bottom) hide)
    )
    (pin "1")
    (pin "2")
    (instances
      (project "sdi-mipi-bridge"
        (path ""
          (reference "C49") (unit 1)
        )
      )
    )
  )

  (symbol (lib_id "sdi-mipi-bridge:C_100n_6V3_0402") (at 265.43 273.05 90) (unit 1)
    (in_bom yes) (on_board yes) (dnp no) (fields_autoplaced)
    (property "Reference" "C53" (at 267.97 269.2335 90)
      (effects (font (size 1.27 1.27)) (justify right))
    )
    (property "Value" "C_100n_6V3_0402" (at 269.24 273.05 0)
      (effects (font (size 1.524 1.524)) hide)
    )
    (property "Footprint" "sdi-mipi-bridge-footprints:C_0402_1005Metric" (at 260.35 267.97 0)
      (effects (font (size 1.524 1.524)) (justify left) hide)
    )
    (property "Datasheet" " " (at 265.43 273.05 0)
      (effects (font (size 1.27 1.27)) hide)
    )
    (property "Manufacturer" "Walsin" (at 255.27 267.97 0)
      (effects (font (size 1.524 1.524)) (justify left) hide)
    )
    (property "MPN" "0402X104K6R3CT" (at 257.81 267.97 0)
      (effects (font (size 1.524 1.524)) (justify left) hide)
    )
    (property "Val" "100n" (at 267.97 271.7735 90)
      (effects (font (size 1.27 1.27)) (justify right))
    )
    (property "License" "Apache-2.0" (at 288.29 252.73 0)
      (effects (font (size 1.27 1.27) (thickness 0.15)) (justify left bottom) hide)
    )
    (property "Author" "Antmicro" (at 290.83 252.73 0)
      (effects (font (size 1.27 1.27) (thickness 0.15)) (justify left bottom) hide)
    )
    (property "Voltage" "" (at 293.37 252.73 0)
      (effects (font (size 1.27 1.27)) (justify left bottom) hide)
    )
    (property "Dielectric" "" (at 295.91 252.73 0)
      (effects (font (size 1.27 1.27)) (justify left bottom) hide)
    )
    (pin "1")
    (pin "2")
    (instances
      (project "sdi-mipi-bridge"
        (path ""
          (reference "C53") (unit 1)
        )
      )
    )
  )

  (symbol (lib_id "sdi-mipi-bridge:GNDA") (at 506.73 113.03 0) (unit 1)
    (in_bom yes) (on_board yes) (dnp no)
    (property "Reference" "#PWR0118" (at 506.73 119.38 0)
      (effects (font (size 1.27 1.27)) hide)
    )
    (property "Value" "GNDA" (at 506.857 117.4242 0)
      (effects (font (size 1.27 1.27)))
    )
    (property "Footprint" "" (at 506.73 113.03 0)
      (effects (font (size 1.27 1.27)) hide)
    )
    (property "Datasheet" "" (at 506.73 113.03 0)
      (effects (font (size 1.27 1.27)) hide)
    )
    (pin "1")
    (instances
      (project "sdi-mipi-bridge"
        (path ""
          (reference "#PWR0118") (unit 1)
        )
      )
    )
  )

  (symbol (lib_id "sdi-mipi-bridge:R_0R_0402") (at 439.42 135.89 0) (mirror y) (unit 1)
    (in_bom yes) (on_board yes) (dnp no)
    (property "Reference" "R41" (at 433.07 134.62 0)
      (effects (font (size 1.27 1.27)))
    )
    (property "Value" "R_0R_0402" (at 419.1 148.59 0)
      (effects (font (size 1.27 1.27) (thickness 0.15)) (justify left bottom) hide)
    )
    (property "Footprint" "sdi-mipi-bridge-footprints:R_0402_1005Metric" (at 419.1 151.13 0)
      (effects (font (size 1.27 1.27) (thickness 0.15)) (justify left bottom) hide)
    )
    (property "Datasheet" "https://industrial.panasonic.com/cdbs/www-data/pdf/RDA0000/AOA0000C301.pdf" (at 419.1 153.67 0)
      (effects (font (size 1.27 1.27) (thickness 0.15)) (justify left bottom) hide)
    )
    (property "Manufacturer" "Panasonic" (at 419.1 158.75 0)
      (effects (font (size 1.27 1.27) (thickness 0.15)) (justify left bottom) hide)
    )
    (property "MPN" "ERJ2GE0R00X" (at 419.1 156.21 0)
      (effects (font (size 1.27 1.27) (thickness 0.15)) (justify left bottom) hide)
    )
    (property "Val" "0R" (at 441.96 135.89 0)
      (effects (font (size 1.27 1.27) (thickness 0.15)) (justify left bottom))
    )
    (property "License" "Apache-2.0" (at 419.1 161.29 0)
      (effects (font (size 1.27 1.27) (thickness 0.15)) (justify left bottom) hide)
    )
    (property "Author" "Antmicro" (at 419.1 163.83 0)
      (effects (font (size 1.27 1.27) (thickness 0.15)) (justify left bottom) hide)
    )
    (property "Tolerance" "~" (at 419.1 146.05 0)
      (effects (font (size 1.27 1.27)) (justify left bottom) hide)
    )
    (property "Current" "1A" (at 419.1 166.37 0)
      (effects (font (size 1.27 1.27) (thickness 0.15)) (justify left bottom) hide)
    )
    (property "DNP" "DNP" (at 439.42 135.89 0)
      (effects (font (size 1.27 1.27)) hide)
    )
    (pin "1")
    (pin "2")
    (instances
      (project "sdi-mipi-bridge"
        (path ""
          (reference "R41") (unit 1)
        )
      )
    )
  )

  (symbol (lib_id "sdi-mipi-bridge:R_0R_0402") (at 439.42 138.43 0) (mirror y) (unit 1)
    (in_bom yes) (on_board yes) (dnp no)
    (property "Reference" "R42" (at 433.07 137.16 0)
      (effects (font (size 1.27 1.27)))
    )
    (property "Value" "R_0R_0402" (at 419.1 151.13 0)
      (effects (font (size 1.27 1.27) (thickness 0.15)) (justify left bottom) hide)
    )
    (property "Footprint" "sdi-mipi-bridge-footprints:R_0402_1005Metric" (at 419.1 153.67 0)
      (effects (font (size 1.27 1.27) (thickness 0.15)) (justify left bottom) hide)
    )
    (property "Datasheet" "https://industrial.panasonic.com/cdbs/www-data/pdf/RDA0000/AOA0000C301.pdf" (at 419.1 156.21 0)
      (effects (font (size 1.27 1.27) (thickness 0.15)) (justify left bottom) hide)
    )
    (property "Manufacturer" "Panasonic" (at 419.1 161.29 0)
      (effects (font (size 1.27 1.27) (thickness 0.15)) (justify left bottom) hide)
    )
    (property "MPN" "ERJ2GE0R00X" (at 419.1 158.75 0)
      (effects (font (size 1.27 1.27) (thickness 0.15)) (justify left bottom) hide)
    )
    (property "Val" "0R" (at 441.96 138.43 0)
      (effects (font (size 1.27 1.27) (thickness 0.15)) (justify left bottom))
    )
    (property "License" "Apache-2.0" (at 419.1 163.83 0)
      (effects (font (size 1.27 1.27) (thickness 0.15)) (justify left bottom) hide)
    )
    (property "Author" "Antmicro" (at 419.1 166.37 0)
      (effects (font (size 1.27 1.27) (thickness 0.15)) (justify left bottom) hide)
    )
    (property "Tolerance" "~" (at 419.1 148.59 0)
      (effects (font (size 1.27 1.27)) (justify left bottom) hide)
    )
    (property "Current" "1A" (at 419.1 168.91 0)
      (effects (font (size 1.27 1.27) (thickness 0.15)) (justify left bottom) hide)
    )
    (property "DNP" "DNP" (at 439.42 138.43 0)
      (effects (font (size 1.27 1.27)) hide)
    )
    (pin "1")
    (pin "2")
    (instances
      (project "sdi-mipi-bridge"
        (path ""
          (reference "R42") (unit 1)
        )
      )
    )
  )

  (symbol (lib_id "sdi-mipi-bridge:GNDREF") (at 444.5 162.56 0) (unit 1)
    (in_bom yes) (on_board yes) (dnp no)
    (property "Reference" "#PWR061" (at 444.5 168.91 0)
      (effects (font (size 1.27 1.27)) hide)
    )
    (property "Value" "GNDREF" (at 444.5 166.37 0)
      (effects (font (size 1.27 1.27)))
    )
    (property "Footprint" "" (at 444.5 162.56 0)
      (effects (font (size 1.27 1.27)) hide)
    )
    (property "Datasheet" "" (at 444.5 162.56 0)
      (effects (font (size 1.27 1.27)) hide)
    )
    (pin "1")
    (instances
      (project "sdi-mipi-bridge"
        (path ""
          (reference "#PWR061") (unit 1)
        )
      )
    )
  )

  (symbol (lib_id "sdi-mipi-bridge:C_100n_6V3_0402") (at 236.22 345.44 90) (unit 1)
    (in_bom yes) (on_board yes) (dnp no) (fields_autoplaced)
    (property "Reference" "C51" (at 238.76 341.6235 90)
      (effects (font (size 1.27 1.27)) (justify right))
    )
    (property "Value" "C_100n_6V3_0402" (at 240.03 345.44 0)
      (effects (font (size 1.524 1.524)) hide)
    )
    (property "Footprint" "sdi-mipi-bridge-footprints:C_0402_1005Metric" (at 231.14 340.36 0)
      (effects (font (size 1.524 1.524)) (justify left) hide)
    )
    (property "Datasheet" " " (at 236.22 345.44 0)
      (effects (font (size 1.27 1.27)) hide)
    )
    (property "Manufacturer" "Walsin" (at 226.06 340.36 0)
      (effects (font (size 1.524 1.524)) (justify left) hide)
    )
    (property "MPN" "0402X104K6R3CT" (at 228.6 340.36 0)
      (effects (font (size 1.524 1.524)) (justify left) hide)
    )
    (property "Val" "100n" (at 238.76 344.1635 90)
      (effects (font (size 1.27 1.27)) (justify right))
    )
    (property "License" "Apache-2.0" (at 259.08 325.12 0)
      (effects (font (size 1.27 1.27) (thickness 0.15)) (justify left bottom) hide)
    )
    (property "Author" "Antmicro" (at 261.62 325.12 0)
      (effects (font (size 1.27 1.27) (thickness 0.15)) (justify left bottom) hide)
    )
    (property "Voltage" "" (at 264.16 325.12 0)
      (effects (font (size 1.27 1.27)) (justify left bottom) hide)
    )
    (property "Dielectric" "" (at 266.7 325.12 0)
      (effects (font (size 1.27 1.27)) (justify left bottom) hide)
    )
    (pin "1")
    (pin "2")
    (instances
      (project "sdi-mipi-bridge"
        (path ""
          (reference "C51") (unit 1)
        )
      )
    )
  )

  (symbol (lib_id "sdi-mipi-bridge:C_1u_0402") (at 228.6 345.44 90) (unit 1)
    (in_bom yes) (on_board yes) (dnp no) (fields_autoplaced)
    (property "Reference" "C47" (at 231.14 341.6235 90)
      (effects (font (size 1.27 1.27)) (justify right))
    )
    (property "Value" "C_1u_0402" (at 232.41 345.44 0)
      (effects (font (size 1.524 1.524)) hide)
    )
    (property "Footprint" "sdi-mipi-bridge-footprints:C_0402_1005Metric" (at 223.52 340.36 0)
      (effects (font (size 1.524 1.524)) (justify left) hide)
    )
    (property "Datasheet" " " (at 228.6 345.44 0)
      (effects (font (size 1.27 1.27)) hide)
    )
    (property "Manufacturer" "TDK" (at 218.44 340.36 0)
      (effects (font (size 1.524 1.524)) (justify left) hide)
    )
    (property "MPN" "C1005X6S1A105K050BC" (at 220.98 340.36 0)
      (effects (font (size 1.524 1.524)) (justify left) hide)
    )
    (property "Val" "1u" (at 231.14 344.1635 90)
      (effects (font (size 1.27 1.27)) (justify right))
    )
    (property "License" "Apache-2.0" (at 251.46 325.12 0)
      (effects (font (size 1.27 1.27) (thickness 0.15)) (justify left bottom) hide)
    )
    (property "Author" "Antmicro" (at 254 325.12 0)
      (effects (font (size 1.27 1.27) (thickness 0.15)) (justify left bottom) hide)
    )
    (property "Voltage" "" (at 256.54 325.12 0)
      (effects (font (size 1.27 1.27)) (justify left bottom) hide)
    )
    (property "Dielectric" "" (at 259.08 325.12 0)
      (effects (font (size 1.27 1.27)) (justify left bottom) hide)
    )
    (pin "1")
    (pin "2")
    (instances
      (project "sdi-mipi-bridge"
        (path ""
          (reference "C47") (unit 1)
        )
      )
    )
  )

  (symbol (lib_id "sdi-mipi-bridge:+1V2") (at 228.6 331.47 0) (unit 1)
    (in_bom yes) (on_board yes) (dnp no)
    (property "Reference" "#PWR036" (at 228.6 335.28 0)
      (effects (font (size 1.27 1.27)) hide)
    )
    (property "Value" "+1V2" (at 228.981 327.0758 0)
      (effects (font (size 1.27 1.27)))
    )
    (property "Footprint" "" (at 228.6 331.47 0)
      (effects (font (size 1.27 1.27)) hide)
    )
    (property "Datasheet" "" (at 228.6 331.47 0)
      (effects (font (size 1.27 1.27)) hide)
    )
    (pin "1")
    (instances
      (project "sdi-mipi-bridge"
        (path ""
          (reference "#PWR036") (unit 1)
        )
      )
    )
  )

  (symbol (lib_id "sdi-mipi-bridge:TP_1mm_SMD") (at 38.1 55.88 180) (unit 1)
    (in_bom yes) (on_board yes) (dnp no) (fields_autoplaced)
    (property "Reference" "TP20" (at 33.02 55.8799 0)
      (effects (font (size 1.27 1.27)) (justify left))
    )
    (property "Value" "TP_1mm_SMD" (at 38.1 53.34 0)
      (effects (font (size 1.27 1.27) (thickness 0.15)) (justify left bottom) hide)
    )
    (property "Footprint" "sdi-mipi-bridge-footprints:Testpoint_smd_1mm" (at 33.02 60.96 0)
      (effects (font (size 1.27 1.27) (thickness 0.15)) (justify left bottom) hide)
    )
    (property "Datasheet" "" (at 33.02 63.5 0)
      (effects (font (size 1.27 1.27) (thickness 0.15)) (justify left bottom) hide)
    )
    (property "MPN" "" (at 38.1 55.88 0)
      (effects (font (size 1.27 1.27)) hide)
    )
    (property "Manufacturer" "" (at 38.1 55.88 0)
      (effects (font (size 1.27 1.27)) hide)
    )
    (property "Author" "Antmicro" (at 22.86 40.64 0)
      (effects (font (size 1.27 1.27) (thickness 0.15)) (justify left bottom) hide)
    )
    (property "License" "Apache-2.0" (at 22.86 38.1 0)
      (effects (font (size 1.27 1.27) (thickness 0.15)) (justify left bottom) hide)
    )
    (pin "1")
    (instances
      (project "sdi-mipi-bridge"
        (path ""
          (reference "TP20") (unit 1)
        )
      )
    )
  )

  (symbol (lib_id "sdi-mipi-bridge:TP_1mm_SMD") (at 38.1 53.34 180) (unit 1)
    (in_bom yes) (on_board yes) (dnp no) (fields_autoplaced)
    (property "Reference" "TP19" (at 33.02 53.3399 0)
      (effects (font (size 1.27 1.27)) (justify left))
    )
    (property "Value" "TP_1mm_SMD" (at 38.1 50.8 0)
      (effects (font (size 1.27 1.27) (thickness 0.15)) (justify left bottom) hide)
    )
    (property "Footprint" "sdi-mipi-bridge-footprints:Testpoint_smd_1mm" (at 33.02 58.42 0)
      (effects (font (size 1.27 1.27) (thickness 0.15)) (justify left bottom) hide)
    )
    (property "Datasheet" "" (at 33.02 60.96 0)
      (effects (font (size 1.27 1.27) (thickness 0.15)) (justify left bottom) hide)
    )
    (property "MPN" "" (at 38.1 53.34 0)
      (effects (font (size 1.27 1.27)) hide)
    )
    (property "Manufacturer" "" (at 38.1 53.34 0)
      (effects (font (size 1.27 1.27)) hide)
    )
    (property "Author" "Antmicro" (at 22.86 38.1 0)
      (effects (font (size 1.27 1.27) (thickness 0.15)) (justify left bottom) hide)
    )
    (property "License" "Apache-2.0" (at 22.86 35.56 0)
      (effects (font (size 1.27 1.27) (thickness 0.15)) (justify left bottom) hide)
    )
    (pin "1")
    (instances
      (project "sdi-mipi-bridge"
        (path ""
          (reference "TP19") (unit 1)
        )
      )
    )
  )

  (symbol (lib_id "sdi-mipi-bridge:C_1u_0402") (at 240.03 379.73 90) (unit 1)
    (in_bom yes) (on_board yes) (dnp no) (fields_autoplaced)
    (property "Reference" "C45" (at 242.57 375.9135 90)
      (effects (font (size 1.27 1.27)) (justify right))
    )
    (property "Value" "C_1u_0402" (at 243.84 379.73 0)
      (effects (font (size 1.524 1.524)) hide)
    )
    (property "Footprint" "sdi-mipi-bridge-footprints:C_0402_1005Metric" (at 234.95 374.65 0)
      (effects (font (size 1.524 1.524)) (justify left) hide)
    )
    (property "Datasheet" " " (at 240.03 379.73 0)
      (effects (font (size 1.27 1.27)) hide)
    )
    (property "Manufacturer" "TDK" (at 229.87 374.65 0)
      (effects (font (size 1.524 1.524)) (justify left) hide)
    )
    (property "MPN" "C1005X6S1A105K050BC" (at 232.41 374.65 0)
      (effects (font (size 1.524 1.524)) (justify left) hide)
    )
    (property "Val" "1u" (at 242.57 378.4535 90)
      (effects (font (size 1.27 1.27)) (justify right))
    )
    (property "License" "Apache-2.0" (at 262.89 359.41 0)
      (effects (font (size 1.27 1.27) (thickness 0.15)) (justify left bottom) hide)
    )
    (property "Author" "Antmicro" (at 265.43 359.41 0)
      (effects (font (size 1.27 1.27) (thickness 0.15)) (justify left bottom) hide)
    )
    (property "Voltage" "" (at 267.97 359.41 0)
      (effects (font (size 1.27 1.27)) (justify left bottom) hide)
    )
    (property "Dielectric" "" (at 270.51 359.41 0)
      (effects (font (size 1.27 1.27)) (justify left bottom) hide)
    )
    (pin "1")
    (pin "2")
    (instances
      (project "sdi-mipi-bridge"
        (path ""
          (reference "C45") (unit 1)
        )
      )
    )
  )

  (symbol (lib_id "sdi-mipi-bridge:GNDREF") (at 240.03 382.27 0) (unit 1)
    (in_bom yes) (on_board yes) (dnp no)
    (property "Reference" "#PWR047" (at 240.03 388.62 0)
      (effects (font (size 1.27 1.27)) hide)
    )
    (property "Value" "GNDREF" (at 240.157 386.6642 0)
      (effects (font (size 1.27 1.27)))
    )
    (property "Footprint" "" (at 240.03 382.27 0)
      (effects (font (size 1.27 1.27)) hide)
    )
    (property "Datasheet" "" (at 240.03 382.27 0)
      (effects (font (size 1.27 1.27)) hide)
    )
    (pin "1")
    (instances
      (project "sdi-mipi-bridge"
        (path ""
          (reference "#PWR047") (unit 1)
        )
      )
    )
  )

  (symbol (lib_id "sdi-mipi-bridge:R_0R_0402") (at 228.6 372.11 0) (unit 1)
    (in_bom yes) (on_board yes) (dnp no) (fields_autoplaced)
    (property "Reference" "R26" (at 231.14 365.76 0)
      (effects (font (size 1.27 1.27)))
    )
    (property "Value" "R_0R_0402" (at 228.6 375.92 0)
      (effects (font (size 1.524 1.524)) hide)
    )
    (property "Footprint" "sdi-mipi-bridge-footprints:R_0402_1005Metric" (at 233.68 367.03 0)
      (effects (font (size 1.524 1.524)) (justify left) hide)
    )
    (property "Datasheet" "https://industrial.panasonic.com/cdbs/www-data/pdf/RDA0000/AOA0000C301.pdf" (at 228.6 372.11 0)
      (effects (font (size 1.27 1.27)) hide)
    )
    (property "Manufacturer" "Panasonic" (at 233.68 361.95 0)
      (effects (font (size 1.524 1.524)) (justify left) hide)
    )
    (property "MPN" "ERJ2GE0R00X" (at 233.68 364.49 0)
      (effects (font (size 1.524 1.524)) (justify left) hide)
    )
    (property "Val" "0R" (at 231.14 368.3 0)
      (effects (font (size 1.27 1.27)))
    )
    (property "License" "Apache-2.0" (at 248.92 397.51 0)
      (effects (font (size 1.27 1.27) (thickness 0.15)) (justify left bottom) hide)
    )
    (property "Author" "Antmicro" (at 248.92 400.05 0)
      (effects (font (size 1.27 1.27) (thickness 0.15)) (justify left bottom) hide)
    )
    (property "Tolerance" "~" (at 248.92 382.27 0)
      (effects (font (size 1.27 1.27)) (justify left bottom) hide)
    )
    (property "Current" "1A" (at 248.92 402.59 0)
      (effects (font (size 1.27 1.27) (thickness 0.15)) (justify left bottom) hide)
    )
    (pin "1")
    (pin "2")
    (instances
      (project "sdi-mipi-bridge"
        (path ""
          (reference "R26") (unit 1)
        )
      )
    )
  )

  (symbol (lib_id "sdi-mipi-bridge:TP_1mm_SMD") (at 38.1 58.42 180) (unit 1)
    (in_bom yes) (on_board yes) (dnp no) (fields_autoplaced)
    (property "Reference" "TP21" (at 33.02 58.4199 0)
      (effects (font (size 1.27 1.27)) (justify left))
    )
    (property "Value" "TP_1mm_SMD" (at 38.1 55.88 0)
      (effects (font (size 1.27 1.27) (thickness 0.15)) (justify left bottom) hide)
    )
    (property "Footprint" "sdi-mipi-bridge-footprints:Testpoint_smd_1mm" (at 33.02 63.5 0)
      (effects (font (size 1.27 1.27) (thickness 0.15)) (justify left bottom) hide)
    )
    (property "Datasheet" "" (at 33.02 66.04 0)
      (effects (font (size 1.27 1.27) (thickness 0.15)) (justify left bottom) hide)
    )
    (property "MPN" "" (at 38.1 58.42 0)
      (effects (font (size 1.27 1.27)) hide)
    )
    (property "Manufacturer" "" (at 38.1 58.42 0)
      (effects (font (size 1.27 1.27)) hide)
    )
    (property "Author" "Antmicro" (at 22.86 43.18 0)
      (effects (font (size 1.27 1.27) (thickness 0.15)) (justify left bottom) hide)
    )
    (property "License" "Apache-2.0" (at 22.86 40.64 0)
      (effects (font (size 1.27 1.27) (thickness 0.15)) (justify left bottom) hide)
    )
    (pin "1")
    (instances
      (project "sdi-mipi-bridge"
        (path ""
          (reference "TP21") (unit 1)
        )
      )
    )
  )

  (symbol (lib_id "sdi-mipi-bridge:R_0R_0402") (at 439.42 130.81 0) (mirror y) (unit 1)
    (in_bom yes) (on_board yes) (dnp no)
    (property "Reference" "R39" (at 433.07 129.54 0)
      (effects (font (size 1.27 1.27)))
    )
    (property "Value" "R_0R_0402" (at 419.1 143.51 0)
      (effects (font (size 1.27 1.27) (thickness 0.15)) (justify left bottom) hide)
    )
    (property "Footprint" "sdi-mipi-bridge-footprints:R_0402_1005Metric" (at 419.1 146.05 0)
      (effects (font (size 1.27 1.27) (thickness 0.15)) (justify left bottom) hide)
    )
    (property "Datasheet" "https://industrial.panasonic.com/cdbs/www-data/pdf/RDA0000/AOA0000C301.pdf" (at 419.1 148.59 0)
      (effects (font (size 1.27 1.27) (thickness 0.15)) (justify left bottom) hide)
    )
    (property "Manufacturer" "Panasonic" (at 419.1 153.67 0)
      (effects (font (size 1.27 1.27) (thickness 0.15)) (justify left bottom) hide)
    )
    (property "MPN" "ERJ2GE0R00X" (at 419.1 151.13 0)
      (effects (font (size 1.27 1.27) (thickness 0.15)) (justify left bottom) hide)
    )
    (property "Val" "0R" (at 441.96 130.81 0)
      (effects (font (size 1.27 1.27) (thickness 0.15)) (justify left bottom))
    )
    (property "License" "Apache-2.0" (at 419.1 156.21 0)
      (effects (font (size 1.27 1.27) (thickness 0.15)) (justify left bottom) hide)
    )
    (property "Author" "Antmicro" (at 419.1 158.75 0)
      (effects (font (size 1.27 1.27) (thickness 0.15)) (justify left bottom) hide)
    )
    (property "Tolerance" "~" (at 419.1 140.97 0)
      (effects (font (size 1.27 1.27)) (justify left bottom) hide)
    )
    (property "Current" "1A" (at 419.1 161.29 0)
      (effects (font (size 1.27 1.27) (thickness 0.15)) (justify left bottom) hide)
    )
    (pin "1")
    (pin "2")
    (instances
      (project "sdi-mipi-bridge"
        (path ""
          (reference "R39") (unit 1)
        )
      )
    )
  )

  (symbol (lib_id "sdi-mipi-bridge:R_0R_0402") (at 439.42 133.35 0) (mirror y) (unit 1)
    (in_bom yes) (on_board yes) (dnp no)
    (property "Reference" "R40" (at 433.07 132.08 0)
      (effects (font (size 1.27 1.27)))
    )
    (property "Value" "R_0R_0402" (at 419.1 146.05 0)
      (effects (font (size 1.27 1.27) (thickness 0.15)) (justify left bottom) hide)
    )
    (property "Footprint" "sdi-mipi-bridge-footprints:R_0402_1005Metric" (at 419.1 148.59 0)
      (effects (font (size 1.27 1.27) (thickness 0.15)) (justify left bottom) hide)
    )
    (property "Datasheet" "https://industrial.panasonic.com/cdbs/www-data/pdf/RDA0000/AOA0000C301.pdf" (at 419.1 151.13 0)
      (effects (font (size 1.27 1.27) (thickness 0.15)) (justify left bottom) hide)
    )
    (property "Manufacturer" "Panasonic" (at 419.1 156.21 0)
      (effects (font (size 1.27 1.27) (thickness 0.15)) (justify left bottom) hide)
    )
    (property "MPN" "ERJ2GE0R00X" (at 419.1 153.67 0)
      (effects (font (size 1.27 1.27) (thickness 0.15)) (justify left bottom) hide)
    )
    (property "Val" "0R" (at 441.96 133.35 0)
      (effects (font (size 1.27 1.27) (thickness 0.15)) (justify left bottom))
    )
    (property "License" "Apache-2.0" (at 419.1 158.75 0)
      (effects (font (size 1.27 1.27) (thickness 0.15)) (justify left bottom) hide)
    )
    (property "Author" "Antmicro" (at 419.1 161.29 0)
      (effects (font (size 1.27 1.27) (thickness 0.15)) (justify left bottom) hide)
    )
    (property "Tolerance" "~" (at 419.1 143.51 0)
      (effects (font (size 1.27 1.27)) (justify left bottom) hide)
    )
    (property "Current" "1A" (at 419.1 163.83 0)
      (effects (font (size 1.27 1.27) (thickness 0.15)) (justify left bottom) hide)
    )
    (pin "1")
    (pin "2")
    (instances
      (project "sdi-mipi-bridge"
        (path ""
          (reference "R40") (unit 1)
        )
      )
    )
  )

  (symbol (lib_id "sdi-mipi-bridge:R_4k7_0402") (at 427.99 241.3 180) (unit 1)
    (in_bom yes) (on_board yes) (dnp no)
    (property "Reference" "R35" (at 420.37 240.03 0)
      (effects (font (size 1.27 1.27)))
    )
    (property "Value" "R_4k7_0402" (at 427.99 237.49 0)
      (effects (font (size 1.27 1.27) (thickness 0.15)) (justify left bottom) hide)
    )
    (property "Footprint" "sdi-mipi-bridge-footprints:R_0402_1005Metric" (at 422.91 246.38 0)
      (effects (font (size 1.27 1.27) (thickness 0.15)) (justify left bottom) hide)
    )
    (property "Datasheet" "https://www.bourns.com/docs/product-datasheets/cr.pdf" (at 427.99 241.3 0)
      (effects (font (size 1.27 1.27) (thickness 0.15)) (justify left bottom) hide)
    )
    (property "Manufacturer" "Bourns" (at 422.91 251.46 0)
      (effects (font (size 1.27 1.27) (thickness 0.15)) (justify left bottom) hide)
    )
    (property "MPN" "CR0402-FX-4701GLF" (at 422.91 248.92 0)
      (effects (font (size 1.27 1.27) (thickness 0.15)) (justify left bottom) hide)
    )
    (property "Val" "4k7" (at 429.26 240.03 0)
      (effects (font (size 1.27 1.27) (thickness 0.15)))
    )
    (property "License" "Apache-2.0" (at 407.67 215.9 0)
      (effects (font (size 1.27 1.27) (thickness 0.15)) (justify left bottom) hide)
    )
    (property "Author" "Antmicro" (at 407.67 213.36 0)
      (effects (font (size 1.27 1.27) (thickness 0.15)) (justify left bottom) hide)
    )
    (property "Tolerance" "1%" (at 407.67 231.14 0)
      (effects (font (size 1.27 1.27)) (justify left bottom) hide)
    )
    (pin "1")
    (pin "2")
    (instances
      (project "sdi-mipi-bridge"
        (path ""
          (reference "R35") (unit 1)
        )
      )
    )
  )

  (symbol (lib_id "sdi-mipi-bridge:R_4k7_0402") (at 427.99 243.84 180) (unit 1)
    (in_bom yes) (on_board yes) (dnp no)
    (property "Reference" "R36" (at 420.37 242.57 0)
      (effects (font (size 1.27 1.27)))
    )
    (property "Value" "R_4k7_0402" (at 427.99 240.03 0)
      (effects (font (size 1.27 1.27) (thickness 0.15)) (justify left bottom) hide)
    )
    (property "Footprint" "sdi-mipi-bridge-footprints:R_0402_1005Metric" (at 422.91 248.92 0)
      (effects (font (size 1.27 1.27) (thickness 0.15)) (justify left bottom) hide)
    )
    (property "Datasheet" "https://www.bourns.com/docs/product-datasheets/cr.pdf" (at 427.99 243.84 0)
      (effects (font (size 1.27 1.27) (thickness 0.15)) (justify left bottom) hide)
    )
    (property "Manufacturer" "Bourns" (at 422.91 254 0)
      (effects (font (size 1.27 1.27) (thickness 0.15)) (justify left bottom) hide)
    )
    (property "MPN" "CR0402-FX-4701GLF" (at 422.91 251.46 0)
      (effects (font (size 1.27 1.27) (thickness 0.15)) (justify left bottom) hide)
    )
    (property "Val" "4k7" (at 429.26 242.57 0)
      (effects (font (size 1.27 1.27) (thickness 0.15)))
    )
    (property "License" "Apache-2.0" (at 407.67 218.44 0)
      (effects (font (size 1.27 1.27) (thickness 0.15)) (justify left bottom) hide)
    )
    (property "Author" "Antmicro" (at 407.67 215.9 0)
      (effects (font (size 1.27 1.27) (thickness 0.15)) (justify left bottom) hide)
    )
    (property "Tolerance" "1%" (at 407.67 233.68 0)
      (effects (font (size 1.27 1.27)) (justify left bottom) hide)
    )
    (pin "1")
    (pin "2")
    (instances
      (project "sdi-mipi-bridge"
        (path ""
          (reference "R36") (unit 1)
        )
      )
    )
  )

  (symbol (lib_id "sdi-mipi-bridge:Conn_FFC_68715014522_ONE-SIDE") (at 461.01 34.29 0) (unit 1)
    (in_bom yes) (on_board yes) (dnp no) (fields_autoplaced)
    (property "Reference" "J3" (at 467.36 96.5199 0)
      (effects (font (size 1.27 1.27)) (justify left))
    )
    (property "Value" "Conn_FFC_68715014522_ONE-SIDE" (at 467.36 99.0599 0)
      (effects (font (size 1.27 1.27) (thickness 0.15)) (justify left) hide)
    )
    (property "Footprint" "sdi-mipi-bridge-footprints:WE_68715014522_ONE-SIDE" (at 480.06 44.45 0)
      (effects (font (size 1.27 1.27) (thickness 0.15)) (justify left bottom) hide)
    )
    (property "Datasheet" "https://www.we-online.com/components/products/datasheet/68715014522.pdf" (at 480.06 46.99 0)
      (effects (font (size 1.27 1.27) (thickness 0.15)) (justify left bottom) hide)
    )
    (property "MPN" "68715014522" (at 467.36 99.0599 0)
      (effects (font (size 1.27 1.27) (thickness 0.15)) (justify left))
    )
    (property "Manufacturer" "Würth Elektronik" (at 480.06 52.07 0)
      (effects (font (size 1.27 1.27) (thickness 0.15)) (justify left bottom) hide)
    )
    (property "Author" "Antmicro" (at 480.06 54.61 0)
      (effects (font (size 1.27 1.27) (thickness 0.15)) (justify left bottom) hide)
    )
    (property "License" "Apache-2.0" (at 480.06 57.15 0)
      (effects (font (size 1.27 1.27) (thickness 0.15)) (justify left bottom) hide)
    )
    (pin "1")
    (pin "10")
    (pin "11")
    (pin "12")
    (pin "13")
    (pin "14")
    (pin "15")
    (pin "16")
    (pin "17")
    (pin "18")
    (pin "19")
    (pin "2")
    (pin "20")
    (pin "21")
    (pin "22")
    (pin "23")
    (pin "24")
    (pin "25")
    (pin "26")
    (pin "27")
    (pin "28")
    (pin "29")
    (pin "3")
    (pin "30")
    (pin "31")
    (pin "32")
    (pin "33")
    (pin "34")
    (pin "35")
    (pin "36")
    (pin "37")
    (pin "38")
    (pin "39")
    (pin "4")
    (pin "40")
    (pin "41")
    (pin "42")
    (pin "43")
    (pin "44")
    (pin "45")
    (pin "46")
    (pin "47")
    (pin "48")
    (pin "49")
    (pin "5")
    (pin "50")
    (pin "6")
    (pin "7")
    (pin "8")
    (pin "9")
    (pin "SH")
    (instances
      (project "sdi-mipi-bridge"
        (path ""
          (reference "J3") (unit 1)
        )
      )
    )
  )

  (symbol (lib_id "sdi-mipi-bridge:R_0R_0402") (at 516.89 59.69 180) (unit 1)
    (in_bom yes) (on_board yes) (dnp no)
    (property "Reference" "R72" (at 510.54 58.42 0)
      (effects (font (size 1.27 1.27)))
    )
    (property "Value" "R_0R_0402" (at 496.57 46.99 0)
      (effects (font (size 1.27 1.27) (thickness 0.15)) (justify left bottom) hide)
    )
    (property "Footprint" "sdi-mipi-bridge-footprints:R_0402_1005Metric" (at 496.57 44.45 0)
      (effects (font (size 1.27 1.27) (thickness 0.15)) (justify left bottom) hide)
    )
    (property "Datasheet" "https://industrial.panasonic.com/cdbs/www-data/pdf/RDA0000/AOA0000C301.pdf" (at 496.57 41.91 0)
      (effects (font (size 1.27 1.27) (thickness 0.15)) (justify left bottom) hide)
    )
    (property "Manufacturer" "Panasonic" (at 496.57 36.83 0)
      (effects (font (size 1.27 1.27) (thickness 0.15)) (justify left bottom) hide)
    )
    (property "MPN" "ERJ2GE0R00X" (at 496.57 39.37 0)
      (effects (font (size 1.27 1.27) (thickness 0.15)) (justify left bottom) hide)
    )
    (property "Val" "0R" (at 519.43 57.15 0)
      (effects (font (size 1.27 1.27) (thickness 0.15)) (justify left bottom))
    )
    (property "License" "Apache-2.0" (at 496.57 34.29 0)
      (effects (font (size 1.27 1.27) (thickness 0.15)) (justify left bottom) hide)
    )
    (property "Author" "Antmicro" (at 496.57 31.75 0)
      (effects (font (size 1.27 1.27) (thickness 0.15)) (justify left bottom) hide)
    )
    (property "Tolerance" "~" (at 496.57 49.53 0)
      (effects (font (size 1.27 1.27)) (justify left bottom) hide)
    )
    (property "Current" "1A" (at 496.57 29.21 0)
      (effects (font (size 1.27 1.27) (thickness 0.15)) (justify left bottom) hide)
    )
    (pin "1")
    (pin "2")
    (instances
      (project "sdi-mipi-bridge"
        (path ""
          (reference "R72") (unit 1)
        )
      )
    )
  )

  (symbol (lib_id "sdi-mipi-bridge:R_0R_0402") (at 516.89 62.23 180) (unit 1)
    (in_bom yes) (on_board yes) (dnp no)
    (property "Reference" "R73" (at 510.54 60.96 0)
      (effects (font (size 1.27 1.27)))
    )
    (property "Value" "R_0R_0402" (at 496.57 49.53 0)
      (effects (font (size 1.27 1.27) (thickness 0.15)) (justify left bottom) hide)
    )
    (property "Footprint" "sdi-mipi-bridge-footprints:R_0402_1005Metric" (at 496.57 46.99 0)
      (effects (font (size 1.27 1.27) (thickness 0.15)) (justify left bottom) hide)
    )
    (property "Datasheet" "https://industrial.panasonic.com/cdbs/www-data/pdf/RDA0000/AOA0000C301.pdf" (at 496.57 44.45 0)
      (effects (font (size 1.27 1.27) (thickness 0.15)) (justify left bottom) hide)
    )
    (property "Manufacturer" "Panasonic" (at 496.57 39.37 0)
      (effects (font (size 1.27 1.27) (thickness 0.15)) (justify left bottom) hide)
    )
    (property "MPN" "ERJ2GE0R00X" (at 496.57 41.91 0)
      (effects (font (size 1.27 1.27) (thickness 0.15)) (justify left bottom) hide)
    )
    (property "Val" "0R" (at 519.43 59.69 0)
      (effects (font (size 1.27 1.27) (thickness 0.15)) (justify left bottom))
    )
    (property "License" "Apache-2.0" (at 496.57 36.83 0)
      (effects (font (size 1.27 1.27) (thickness 0.15)) (justify left bottom) hide)
    )
    (property "Author" "Antmicro" (at 496.57 34.29 0)
      (effects (font (size 1.27 1.27) (thickness 0.15)) (justify left bottom) hide)
    )
    (property "Tolerance" "~" (at 496.57 52.07 0)
      (effects (font (size 1.27 1.27)) (justify left bottom) hide)
    )
    (property "Current" "1A" (at 496.57 31.75 0)
      (effects (font (size 1.27 1.27) (thickness 0.15)) (justify left bottom) hide)
    )
    (pin "1")
    (pin "2")
    (instances
      (project "sdi-mipi-bridge"
        (path ""
          (reference "R73") (unit 1)
        )
      )
    )
  )

  (symbol (lib_id "sdi-mipi-bridge:R_0R_0402") (at 516.89 64.77 180) (unit 1)
    (in_bom yes) (on_board yes) (dnp no)
    (property "Reference" "R74" (at 510.54 63.5 0)
      (effects (font (size 1.27 1.27)))
    )
    (property "Value" "R_0R_0402" (at 496.57 52.07 0)
      (effects (font (size 1.27 1.27) (thickness 0.15)) (justify left bottom) hide)
    )
    (property "Footprint" "sdi-mipi-bridge-footprints:R_0402_1005Metric" (at 496.57 49.53 0)
      (effects (font (size 1.27 1.27) (thickness 0.15)) (justify left bottom) hide)
    )
    (property "Datasheet" "https://industrial.panasonic.com/cdbs/www-data/pdf/RDA0000/AOA0000C301.pdf" (at 496.57 46.99 0)
      (effects (font (size 1.27 1.27) (thickness 0.15)) (justify left bottom) hide)
    )
    (property "Manufacturer" "Panasonic" (at 496.57 41.91 0)
      (effects (font (size 1.27 1.27) (thickness 0.15)) (justify left bottom) hide)
    )
    (property "MPN" "ERJ2GE0R00X" (at 496.57 44.45 0)
      (effects (font (size 1.27 1.27) (thickness 0.15)) (justify left bottom) hide)
    )
    (property "Val" "0R" (at 519.43 62.23 0)
      (effects (font (size 1.27 1.27) (thickness 0.15)) (justify left bottom))
    )
    (property "License" "Apache-2.0" (at 496.57 39.37 0)
      (effects (font (size 1.27 1.27) (thickness 0.15)) (justify left bottom) hide)
    )
    (property "Author" "Antmicro" (at 496.57 36.83 0)
      (effects (font (size 1.27 1.27) (thickness 0.15)) (justify left bottom) hide)
    )
    (property "Tolerance" "~" (at 496.57 54.61 0)
      (effects (font (size 1.27 1.27)) (justify left bottom) hide)
    )
    (property "Current" "1A" (at 496.57 34.29 0)
      (effects (font (size 1.27 1.27) (thickness 0.15)) (justify left bottom) hide)
    )
    (pin "1")
    (pin "2")
    (instances
      (project "sdi-mipi-bridge"
        (path ""
          (reference "R74") (unit 1)
        )
      )
    )
  )

  (symbol (lib_id "sdi-mipi-bridge:GNDREF") (at 524.51 349.25 0) (unit 1)
    (in_bom yes) (on_board yes) (dnp no)
    (property "Reference" "#PWR064" (at 524.51 355.6 0)
      (effects (font (size 1.27 1.27)) hide)
    )
    (property "Value" "GNDREF" (at 524.637 353.6442 0)
      (effects (font (size 1.27 1.27)))
    )
    (property "Footprint" "" (at 524.51 349.25 0)
      (effects (font (size 1.27 1.27)) hide)
    )
    (property "Datasheet" "" (at 524.51 349.25 0)
      (effects (font (size 1.27 1.27)) hide)
    )
    (pin "1")
    (instances
      (project "sdi-mipi-bridge"
        (path ""
          (reference "#PWR064") (unit 1)
        )
      )
    )
  )

  (symbol (lib_id "sdi-mipi-bridge:C_2u2_0402") (at 228.6 233.68 90) (unit 1)
    (in_bom yes) (on_board yes) (dnp no) (fields_autoplaced)
    (property "Reference" "C37" (at 231.14 229.8635 90)
      (effects (font (size 1.27 1.27)) (justify right))
    )
    (property "Value" "C_2u2_0402" (at 232.41 233.68 0)
      (effects (font (size 1.524 1.524)) hide)
    )
    (property "Footprint" "sdi-mipi-bridge-footprints:C_0402_1005Metric" (at 223.52 228.6 0)
      (effects (font (size 1.524 1.524)) (justify left) hide)
    )
    (property "Datasheet" " " (at 228.6 233.68 0)
      (effects (font (size 1.27 1.27)) hide)
    )
    (property "Manufacturer" "TDK" (at 218.44 228.6 0)
      (effects (font (size 1.524 1.524)) (justify left) hide)
    )
    (property "MPN" "C1005X5R1A225K050BC" (at 220.98 228.6 0)
      (effects (font (size 1.524 1.524)) (justify left) hide)
    )
    (property "Val" "2u2" (at 231.14 232.4035 90)
      (effects (font (size 1.27 1.27)) (justify right))
    )
    (property "License" "Apache-2.0" (at 251.46 213.36 0)
      (effects (font (size 1.27 1.27) (thickness 0.15)) (justify left bottom) hide)
    )
    (property "Author" "Antmicro" (at 254 213.36 0)
      (effects (font (size 1.27 1.27) (thickness 0.15)) (justify left bottom) hide)
    )
    (property "Voltage" "" (at 256.54 213.36 0)
      (effects (font (size 1.27 1.27)) (justify left bottom) hide)
    )
    (property "Dielectric" "" (at 259.08 213.36 0)
      (effects (font (size 1.27 1.27)) (justify left bottom) hide)
    )
    (pin "1")
    (pin "2")
    (instances
      (project "sdi-mipi-bridge"
        (path ""
          (reference "C37") (unit 1)
        )
      )
    )
  )

  (symbol (lib_id "sdi-mipi-bridge:GNDREF") (at 228.6 233.68 0) (unit 1)
    (in_bom yes) (on_board yes) (dnp no)
    (property "Reference" "#PWR038" (at 228.6 240.03 0)
      (effects (font (size 1.27 1.27)) hide)
    )
    (property "Value" "GNDREF" (at 228.727 238.0742 0)
      (effects (font (size 1.27 1.27)))
    )
    (property "Footprint" "" (at 228.6 233.68 0)
      (effects (font (size 1.27 1.27)) hide)
    )
    (property "Datasheet" "" (at 228.6 233.68 0)
      (effects (font (size 1.27 1.27)) hide)
    )
    (pin "1")
    (instances
      (project "sdi-mipi-bridge"
        (path ""
          (reference "#PWR038") (unit 1)
        )
      )
    )
  )

  (symbol (lib_id "sdi-mipi-bridge:R_4k7_0402") (at 427.99 254 180) (unit 1)
    (in_bom yes) (on_board yes) (dnp no)
    (property "Reference" "R95" (at 420.37 252.73 0)
      (effects (font (size 1.27 1.27)))
    )
    (property "Value" "R_4k7_0402" (at 427.99 250.19 0)
      (effects (font (size 1.27 1.27) (thickness 0.15)) (justify left bottom) hide)
    )
    (property "Footprint" "sdi-mipi-bridge-footprints:R_0402_1005Metric" (at 422.91 259.08 0)
      (effects (font (size 1.27 1.27) (thickness 0.15)) (justify left bottom) hide)
    )
    (property "Datasheet" "https://www.bourns.com/docs/product-datasheets/cr.pdf" (at 427.99 254 0)
      (effects (font (size 1.27 1.27) (thickness 0.15)) (justify left bottom) hide)
    )
    (property "Manufacturer" "Bourns" (at 422.91 264.16 0)
      (effects (font (size 1.27 1.27) (thickness 0.15)) (justify left bottom) hide)
    )
    (property "MPN" "CR0402-FX-4701GLF" (at 422.91 261.62 0)
      (effects (font (size 1.27 1.27) (thickness 0.15)) (justify left bottom) hide)
    )
    (property "Val" "4k7" (at 429.26 252.73 0)
      (effects (font (size 1.27 1.27) (thickness 0.15)))
    )
    (property "License" "Apache-2.0" (at 407.67 228.6 0)
      (effects (font (size 1.27 1.27) (thickness 0.15)) (justify left bottom) hide)
    )
    (property "Author" "Antmicro" (at 407.67 226.06 0)
      (effects (font (size 1.27 1.27) (thickness 0.15)) (justify left bottom) hide)
    )
    (property "Tolerance" "1%" (at 407.67 243.84 0)
      (effects (font (size 1.27 1.27)) (justify left bottom) hide)
    )
    (pin "1")
    (pin "2")
    (instances
      (project "sdi-mipi-bridge"
        (path ""
          (reference "R95") (unit 1)
        )
      )
    )
  )

  (symbol (lib_id "sdi-mipi-bridge:R_30R_0402") (at 450.85 256.54 0) (unit 1)
    (in_bom yes) (on_board yes) (dnp no)
    (property "Reference" "R96" (at 449.58 255.27 0)
      (effects (font (size 1.27 1.27)))
    )
    (property "Value" "R_30R_0402" (at 450.85 260.35 0)
      (effects (font (size 1.27 1.27) (thickness 0.15)) (justify left bottom) hide)
    )
    (property "Footprint" "sdi-mipi-bridge-footprints:R_0402_1005Metric" (at 455.93 251.46 0)
      (effects (font (size 1.27 1.27) (thickness 0.15)) (justify left bottom) hide)
    )
    (property "Datasheet" "https://www.bourns.com/docs/product-datasheets/cr.pdf" (at 450.85 256.54 0)
      (effects (font (size 1.27 1.27) (thickness 0.15)) (justify left bottom) hide)
    )
    (property "Manufacturer" "Bourns" (at 455.93 246.38 0)
      (effects (font (size 1.27 1.27) (thickness 0.15)) (justify left bottom) hide)
    )
    (property "MPN" "CR0402-FX-30R0GLF" (at 455.93 248.92 0)
      (effects (font (size 1.27 1.27) (thickness 0.15)) (justify left bottom) hide)
    )
    (property "Val" "30R" (at 455.93 256.54 0)
      (effects (font (size 1.27 1.27) (thickness 0.15)) (justify left bottom))
    )
    (property "License" "Apache-2.0" (at 471.17 281.94 0)
      (effects (font (size 1.27 1.27) (thickness 0.15)) (justify left bottom) hide)
    )
    (property "Author" "Antmicro" (at 471.17 284.48 0)
      (effects (font (size 1.27 1.27) (thickness 0.15)) (justify left bottom) hide)
    )
    (property "Tolerance" "1%" (at 471.17 266.7 0)
      (effects (font (size 1.27 1.27)) (justify left bottom) hide)
    )
    (pin "1")
    (pin "2")
    (instances
      (project "sdi-mipi-bridge"
        (path ""
          (reference "R96") (unit 1)
        )
      )
    )
  )

  (symbol (lib_id "sdi-mipi-bridge:FB_120Z_2A_0603") (at 228.6 219.71 270) (unit 1)
    (in_bom yes) (on_board yes) (dnp no) (fields_autoplaced)
    (property "Reference" "FB1" (at 232.41 218.44 90)
      (effects (font (size 1.27 1.27)) (justify left))
    )
    (property "Value" "BLM18PG121SH1D" (at 232.41 222.25 90)
      (effects (font (size 1.524 1.524)) (justify left))
    )
    (property "Footprint" "sdi-mipi-bridge-footprints:FB_0603_1608Metric" (at 233.68 224.79 0)
      (effects (font (size 1.524 1.524)) (justify left) hide)
    )
    (property "Datasheet" "https://www.murata.com/en-us/products/productdata/8796738650142/ENFA0003.pdf" (at 236.22 224.79 0)
      (effects (font (size 1.524 1.524)) (justify left) hide)
    )
    (property "MPN" "BLM18PG121SN1D" (at 241.3 224.79 0)
      (effects (font (size 1.524 1.524)) (justify left) hide)
    )
    (property "Manufacturer" "Murata" (at 256.54 224.79 0)
      (effects (font (size 1.524 1.524)) (justify left) hide)
    )
    (property "Author" "Antmicro" (at 210.82 234.95 0)
      (effects (font (size 1.27 1.27) (thickness 0.15)) (justify left bottom) hide)
    )
    (property "License" "Apache-2.0" (at 208.28 234.95 0)
      (effects (font (size 1.27 1.27) (thickness 0.15)) (justify left bottom) hide)
    )
    (pin "1")
    (pin "2")
    (instances
      (project "sdi-mipi-bridge"
        (path ""
          (reference "FB1") (unit 1)
        )
      )
    )
  )

  (symbol (lib_id "sdi-mipi-bridge:FB_120Z_2A_0603") (at 228.6 337.82 90) (unit 1)
    (in_bom yes) (on_board yes) (dnp no) (fields_autoplaced)
    (property "Reference" "FB3" (at 231.14 334.048 90)
      (effects (font (size 1.27 1.27)) (justify right))
    )
    (property "Value" "BLM18PG121SH1D" (at 231.14 336.588 90)
      (effects (font (size 1.27 1.27)) (justify right))
    )
    (property "Footprint" "sdi-mipi-bridge-footprints:FB_0603_1608Metric" (at 223.52 332.74 0)
      (effects (font (size 1.524 1.524)) (justify left) hide)
    )
    (property "Datasheet" "https://www.murata.com/en-us/products/productdata/8796738650142/ENFA0003.pdf" (at 220.98 332.74 0)
      (effects (font (size 1.524 1.524)) (justify left) hide)
    )
    (property "MPN" "BLM18PG121SN1D" (at 215.9 332.74 0)
      (effects (font (size 1.524 1.524)) (justify left) hide)
    )
    (property "Manufacturer" "Murata" (at 200.66 332.74 0)
      (effects (font (size 1.524 1.524)) (justify left) hide)
    )
    (property "Author" "Antmicro" (at 246.38 322.58 0)
      (effects (font (size 1.27 1.27) (thickness 0.15)) (justify left bottom) hide)
    )
    (property "License" "Apache-2.0" (at 248.92 322.58 0)
      (effects (font (size 1.27 1.27) (thickness 0.15)) (justify left bottom) hide)
    )
    (pin "1")
    (pin "2")
    (instances
      (project "sdi-mipi-bridge"
        (path ""
          (reference "FB3") (unit 1)
        )
      )
    )
  )

  (symbol (lib_id "sdi-mipi-bridge:GNDREF") (at 228.6 274.32 0) (unit 1)
    (in_bom yes) (on_board yes) (dnp no)
    (property "Reference" "#PWR040" (at 228.6 280.67 0)
      (effects (font (size 1.27 1.27)) hide)
    )
    (property "Value" "GNDREF" (at 228.727 278.7142 0)
      (effects (font (size 1.27 1.27)))
    )
    (property "Footprint" "" (at 228.6 274.32 0)
      (effects (font (size 1.27 1.27)) hide)
    )
    (property "Datasheet" "" (at 228.6 274.32 0)
      (effects (font (size 1.27 1.27)) hide)
    )
    (pin "1")
    (instances
      (project "sdi-mipi-bridge"
        (path ""
          (reference "#PWR040") (unit 1)
        )
      )
    )
  )

  (symbol (lib_id "sdi-mipi-bridge:TP_0.75mm_SMD") (at 99.06 44.45 0) (unit 1)
    (in_bom yes) (on_board yes) (dnp no) (fields_autoplaced)
    (property "Reference" "TP7" (at 104.14 44.4499 0)
      (effects (font (size 1.27 1.27)) (justify left))
    )
    (property "Value" "TP_0.75mm_SMD" (at 116.84 52.07 0)
      (effects (font (size 1.27 1.27) (thickness 0.15)) (justify left bottom) hide)
    )
    (property "Footprint" "sdi-mipi-bridge-footprints:TP_SMD_0.75mm" (at 116.84 54.61 0)
      (effects (font (size 1.27 1.27) (thickness 0.15)) (justify left bottom) hide)
    )
    (property "Datasheet" "" (at 116.84 57.15 0)
      (effects (font (size 1.27 1.27) (thickness 0.15)) (justify left bottom) hide)
    )
    (property "MPN" "" (at 116.84 59.69 0)
      (effects (font (size 1.27 1.27) (thickness 0.15)) (justify left bottom) hide)
    )
    (property "Manufacturer" "" (at 116.84 62.23 0)
      (effects (font (size 1.27 1.27) (thickness 0.15)) (justify left bottom) hide)
    )
    (property "Author" "Antmicro" (at 116.84 64.77 0)
      (effects (font (size 1.27 1.27) (thickness 0.15)) (justify left bottom) hide)
    )
    (property "License" "Apache-2.0" (at 116.84 67.31 0)
      (effects (font (size 1.27 1.27) (thickness 0.15)) (justify left bottom) hide)
    )
    (pin "1")
    (instances
      (project "sdi-mipi-bridge"
        (path ""
          (reference "TP7") (unit 1)
        )
      )
    )
  )

  (symbol (lib_id "sdi-mipi-bridge:TP_0.75mm_SMD") (at 99.06 46.99 0) (unit 1)
    (in_bom yes) (on_board yes) (dnp no) (fields_autoplaced)
    (property "Reference" "TP8" (at 104.14 46.9899 0)
      (effects (font (size 1.27 1.27)) (justify left))
    )
    (property "Value" "TP_0.75mm_SMD" (at 116.84 54.61 0)
      (effects (font (size 1.27 1.27) (thickness 0.15)) (justify left bottom) hide)
    )
    (property "Footprint" "sdi-mipi-bridge-footprints:TP_SMD_0.75mm" (at 116.84 57.15 0)
      (effects (font (size 1.27 1.27) (thickness 0.15)) (justify left bottom) hide)
    )
    (property "Datasheet" "" (at 116.84 59.69 0)
      (effects (font (size 1.27 1.27) (thickness 0.15)) (justify left bottom) hide)
    )
    (property "MPN" "" (at 116.84 62.23 0)
      (effects (font (size 1.27 1.27) (thickness 0.15)) (justify left bottom) hide)
    )
    (property "Manufacturer" "" (at 116.84 64.77 0)
      (effects (font (size 1.27 1.27) (thickness 0.15)) (justify left bottom) hide)
    )
    (property "Author" "Antmicro" (at 116.84 67.31 0)
      (effects (font (size 1.27 1.27) (thickness 0.15)) (justify left bottom) hide)
    )
    (property "License" "Apache-2.0" (at 116.84 69.85 0)
      (effects (font (size 1.27 1.27) (thickness 0.15)) (justify left bottom) hide)
    )
    (pin "1")
    (instances
      (project "sdi-mipi-bridge"
        (path ""
          (reference "TP8") (unit 1)
        )
      )
    )
  )

  (symbol (lib_id "sdi-mipi-bridge:TP_0.75mm_SMD") (at 99.06 49.53 0) (unit 1)
    (in_bom yes) (on_board yes) (dnp no) (fields_autoplaced)
    (property "Reference" "TP9" (at 104.14 49.5299 0)
      (effects (font (size 1.27 1.27)) (justify left))
    )
    (property "Value" "TP_0.75mm_SMD" (at 116.84 57.15 0)
      (effects (font (size 1.27 1.27) (thickness 0.15)) (justify left bottom) hide)
    )
    (property "Footprint" "sdi-mipi-bridge-footprints:TP_SMD_0.75mm" (at 116.84 59.69 0)
      (effects (font (size 1.27 1.27) (thickness 0.15)) (justify left bottom) hide)
    )
    (property "Datasheet" "" (at 116.84 62.23 0)
      (effects (font (size 1.27 1.27) (thickness 0.15)) (justify left bottom) hide)
    )
    (property "MPN" "" (at 116.84 64.77 0)
      (effects (font (size 1.27 1.27) (thickness 0.15)) (justify left bottom) hide)
    )
    (property "Manufacturer" "" (at 116.84 67.31 0)
      (effects (font (size 1.27 1.27) (thickness 0.15)) (justify left bottom) hide)
    )
    (property "Author" "Antmicro" (at 116.84 69.85 0)
      (effects (font (size 1.27 1.27) (thickness 0.15)) (justify left bottom) hide)
    )
    (property "License" "Apache-2.0" (at 116.84 72.39 0)
      (effects (font (size 1.27 1.27) (thickness 0.15)) (justify left bottom) hide)
    )
    (pin "1")
    (instances
      (project "sdi-mipi-bridge"
        (path ""
          (reference "TP9") (unit 1)
        )
      )
    )
  )

  (symbol (lib_id "sdi-mipi-bridge:TP_0.75mm_SMD") (at 99.06 52.07 0) (unit 1)
    (in_bom yes) (on_board yes) (dnp no) (fields_autoplaced)
    (property "Reference" "TP10" (at 104.14 52.0699 0)
      (effects (font (size 1.27 1.27)) (justify left))
    )
    (property "Value" "TP_0.75mm_SMD" (at 116.84 59.69 0)
      (effects (font (size 1.27 1.27) (thickness 0.15)) (justify left bottom) hide)
    )
    (property "Footprint" "sdi-mipi-bridge-footprints:TP_SMD_0.75mm" (at 116.84 62.23 0)
      (effects (font (size 1.27 1.27) (thickness 0.15)) (justify left bottom) hide)
    )
    (property "Datasheet" "" (at 116.84 64.77 0)
      (effects (font (size 1.27 1.27) (thickness 0.15)) (justify left bottom) hide)
    )
    (property "MPN" "" (at 116.84 67.31 0)
      (effects (font (size 1.27 1.27) (thickness 0.15)) (justify left bottom) hide)
    )
    (property "Manufacturer" "" (at 116.84 69.85 0)
      (effects (font (size 1.27 1.27) (thickness 0.15)) (justify left bottom) hide)
    )
    (property "Author" "Antmicro" (at 116.84 72.39 0)
      (effects (font (size 1.27 1.27) (thickness 0.15)) (justify left bottom) hide)
    )
    (property "License" "Apache-2.0" (at 116.84 74.93 0)
      (effects (font (size 1.27 1.27) (thickness 0.15)) (justify left bottom) hide)
    )
    (pin "1")
    (instances
      (project "sdi-mipi-bridge"
        (path ""
          (reference "TP10") (unit 1)
        )
      )
    )
  )

  (symbol (lib_id "sdi-mipi-bridge:TP_0.75mm_SMD") (at 99.06 54.61 0) (unit 1)
    (in_bom yes) (on_board yes) (dnp no) (fields_autoplaced)
    (property "Reference" "TP11" (at 104.14 54.6099 0)
      (effects (font (size 1.27 1.27)) (justify left))
    )
    (property "Value" "TP_0.75mm_SMD" (at 116.84 62.23 0)
      (effects (font (size 1.27 1.27) (thickness 0.15)) (justify left bottom) hide)
    )
    (property "Footprint" "sdi-mipi-bridge-footprints:TP_SMD_0.75mm" (at 116.84 64.77 0)
      (effects (font (size 1.27 1.27) (thickness 0.15)) (justify left bottom) hide)
    )
    (property "Datasheet" "" (at 116.84 67.31 0)
      (effects (font (size 1.27 1.27) (thickness 0.15)) (justify left bottom) hide)
    )
    (property "MPN" "" (at 116.84 69.85 0)
      (effects (font (size 1.27 1.27) (thickness 0.15)) (justify left bottom) hide)
    )
    (property "Manufacturer" "" (at 116.84 72.39 0)
      (effects (font (size 1.27 1.27) (thickness 0.15)) (justify left bottom) hide)
    )
    (property "Author" "Antmicro" (at 116.84 74.93 0)
      (effects (font (size 1.27 1.27) (thickness 0.15)) (justify left bottom) hide)
    )
    (property "License" "Apache-2.0" (at 116.84 77.47 0)
      (effects (font (size 1.27 1.27) (thickness 0.15)) (justify left bottom) hide)
    )
    (pin "1")
    (instances
      (project "sdi-mipi-bridge"
        (path ""
          (reference "TP11") (unit 1)
        )
      )
    )
  )

  (symbol (lib_id "sdi-mipi-bridge:TP_0.75mm_SMD") (at 99.06 57.15 0) (unit 1)
    (in_bom yes) (on_board yes) (dnp no) (fields_autoplaced)
    (property "Reference" "TP12" (at 104.14 57.1499 0)
      (effects (font (size 1.27 1.27)) (justify left))
    )
    (property "Value" "TP_0.75mm_SMD" (at 116.84 64.77 0)
      (effects (font (size 1.27 1.27) (thickness 0.15)) (justify left bottom) hide)
    )
    (property "Footprint" "sdi-mipi-bridge-footprints:TP_SMD_0.75mm" (at 116.84 67.31 0)
      (effects (font (size 1.27 1.27) (thickness 0.15)) (justify left bottom) hide)
    )
    (property "Datasheet" "" (at 116.84 69.85 0)
      (effects (font (size 1.27 1.27) (thickness 0.15)) (justify left bottom) hide)
    )
    (property "MPN" "" (at 116.84 72.39 0)
      (effects (font (size 1.27 1.27) (thickness 0.15)) (justify left bottom) hide)
    )
    (property "Manufacturer" "" (at 116.84 74.93 0)
      (effects (font (size 1.27 1.27) (thickness 0.15)) (justify left bottom) hide)
    )
    (property "Author" "Antmicro" (at 116.84 77.47 0)
      (effects (font (size 1.27 1.27) (thickness 0.15)) (justify left bottom) hide)
    )
    (property "License" "Apache-2.0" (at 116.84 80.01 0)
      (effects (font (size 1.27 1.27) (thickness 0.15)) (justify left bottom) hide)
    )
    (pin "1")
    (instances
      (project "sdi-mipi-bridge"
        (path ""
          (reference "TP12") (unit 1)
        )
      )
    )
  )

  (symbol (lib_id "sdi-mipi-bridge:TP_0.75mm_SMD") (at 99.06 59.69 0) (unit 1)
    (in_bom yes) (on_board yes) (dnp no) (fields_autoplaced)
    (property "Reference" "TP13" (at 104.14 59.6899 0)
      (effects (font (size 1.27 1.27)) (justify left))
    )
    (property "Value" "TP_0.75mm_SMD" (at 116.84 67.31 0)
      (effects (font (size 1.27 1.27) (thickness 0.15)) (justify left bottom) hide)
    )
    (property "Footprint" "sdi-mipi-bridge-footprints:TP_SMD_0.75mm" (at 116.84 69.85 0)
      (effects (font (size 1.27 1.27) (thickness 0.15)) (justify left bottom) hide)
    )
    (property "Datasheet" "" (at 116.84 72.39 0)
      (effects (font (size 1.27 1.27) (thickness 0.15)) (justify left bottom) hide)
    )
    (property "MPN" "" (at 116.84 74.93 0)
      (effects (font (size 1.27 1.27) (thickness 0.15)) (justify left bottom) hide)
    )
    (property "Manufacturer" "" (at 116.84 77.47 0)
      (effects (font (size 1.27 1.27) (thickness 0.15)) (justify left bottom) hide)
    )
    (property "Author" "Antmicro" (at 116.84 80.01 0)
      (effects (font (size 1.27 1.27) (thickness 0.15)) (justify left bottom) hide)
    )
    (property "License" "Apache-2.0" (at 116.84 82.55 0)
      (effects (font (size 1.27 1.27) (thickness 0.15)) (justify left bottom) hide)
    )
    (pin "1")
    (instances
      (project "sdi-mipi-bridge"
        (path ""
          (reference "TP13") (unit 1)
        )
      )
    )
  )

  (symbol (lib_id "sdi-mipi-bridge:TP_0.75mm_SMD") (at 99.06 62.23 0) (unit 1)
    (in_bom yes) (on_board yes) (dnp no) (fields_autoplaced)
    (property "Reference" "TP14" (at 104.14 62.2299 0)
      (effects (font (size 1.27 1.27)) (justify left))
    )
    (property "Value" "TP_0.75mm_SMD" (at 116.84 69.85 0)
      (effects (font (size 1.27 1.27) (thickness 0.15)) (justify left bottom) hide)
    )
    (property "Footprint" "sdi-mipi-bridge-footprints:TP_SMD_0.75mm" (at 116.84 72.39 0)
      (effects (font (size 1.27 1.27) (thickness 0.15)) (justify left bottom) hide)
    )
    (property "Datasheet" "" (at 116.84 74.93 0)
      (effects (font (size 1.27 1.27) (thickness 0.15)) (justify left bottom) hide)
    )
    (property "MPN" "" (at 116.84 77.47 0)
      (effects (font (size 1.27 1.27) (thickness 0.15)) (justify left bottom) hide)
    )
    (property "Manufacturer" "" (at 116.84 80.01 0)
      (effects (font (size 1.27 1.27) (thickness 0.15)) (justify left bottom) hide)
    )
    (property "Author" "Antmicro" (at 116.84 82.55 0)
      (effects (font (size 1.27 1.27) (thickness 0.15)) (justify left bottom) hide)
    )
    (property "License" "Apache-2.0" (at 116.84 85.09 0)
      (effects (font (size 1.27 1.27) (thickness 0.15)) (justify left bottom) hide)
    )
    (pin "1")
    (instances
      (project "sdi-mipi-bridge"
        (path ""
          (reference "TP14") (unit 1)
        )
      )
    )
  )

  (symbol (lib_id "sdi-mipi-bridge:TP_0.75mm_SMD") (at 99.06 64.77 0) (unit 1)
    (in_bom yes) (on_board yes) (dnp no) (fields_autoplaced)
    (property "Reference" "TP15" (at 104.14 64.7699 0)
      (effects (font (size 1.27 1.27)) (justify left))
    )
    (property "Value" "TP_0.75mm_SMD" (at 116.84 72.39 0)
      (effects (font (size 1.27 1.27) (thickness 0.15)) (justify left bottom) hide)
    )
    (property "Footprint" "sdi-mipi-bridge-footprints:TP_SMD_0.75mm" (at 116.84 74.93 0)
      (effects (font (size 1.27 1.27) (thickness 0.15)) (justify left bottom) hide)
    )
    (property "Datasheet" "" (at 116.84 77.47 0)
      (effects (font (size 1.27 1.27) (thickness 0.15)) (justify left bottom) hide)
    )
    (property "MPN" "" (at 116.84 80.01 0)
      (effects (font (size 1.27 1.27) (thickness 0.15)) (justify left bottom) hide)
    )
    (property "Manufacturer" "" (at 116.84 82.55 0)
      (effects (font (size 1.27 1.27) (thickness 0.15)) (justify left bottom) hide)
    )
    (property "Author" "Antmicro" (at 116.84 85.09 0)
      (effects (font (size 1.27 1.27) (thickness 0.15)) (justify left bottom) hide)
    )
    (property "License" "Apache-2.0" (at 116.84 87.63 0)
      (effects (font (size 1.27 1.27) (thickness 0.15)) (justify left bottom) hide)
    )
    (pin "1")
    (instances
      (project "sdi-mipi-bridge"
        (path ""
          (reference "TP15") (unit 1)
        )
      )
    )
  )

  (symbol (lib_id "sdi-mipi-bridge:TP_0.75mm_SMD") (at 99.06 67.31 0) (unit 1)
    (in_bom yes) (on_board yes) (dnp no) (fields_autoplaced)
    (property "Reference" "TP16" (at 104.14 67.3099 0)
      (effects (font (size 1.27 1.27)) (justify left))
    )
    (property "Value" "TP_0.75mm_SMD" (at 116.84 74.93 0)
      (effects (font (size 1.27 1.27) (thickness 0.15)) (justify left bottom) hide)
    )
    (property "Footprint" "sdi-mipi-bridge-footprints:TP_SMD_0.75mm" (at 116.84 77.47 0)
      (effects (font (size 1.27 1.27) (thickness 0.15)) (justify left bottom) hide)
    )
    (property "Datasheet" "" (at 116.84 80.01 0)
      (effects (font (size 1.27 1.27) (thickness 0.15)) (justify left bottom) hide)
    )
    (property "MPN" "" (at 116.84 82.55 0)
      (effects (font (size 1.27 1.27) (thickness 0.15)) (justify left bottom) hide)
    )
    (property "Manufacturer" "" (at 116.84 85.09 0)
      (effects (font (size 1.27 1.27) (thickness 0.15)) (justify left bottom) hide)
    )
    (property "Author" "Antmicro" (at 116.84 87.63 0)
      (effects (font (size 1.27 1.27) (thickness 0.15)) (justify left bottom) hide)
    )
    (property "License" "Apache-2.0" (at 116.84 90.17 0)
      (effects (font (size 1.27 1.27) (thickness 0.15)) (justify left bottom) hide)
    )
    (pin "1")
    (instances
      (project "sdi-mipi-bridge"
        (path ""
          (reference "TP16") (unit 1)
        )
      )
    )
  )

  (symbol (lib_id "sdi-mipi-bridge:GNDREF") (at 49.53 337.82 0) (unit 1)
    (in_bom yes) (on_board yes) (dnp no)
    (property "Reference" "#PWR0142" (at 49.53 344.17 0)
      (effects (font (size 1.27 1.27)) hide)
    )
    (property "Value" "GNDREF" (at 49.657 342.2142 0)
      (effects (font (size 1.27 1.27)))
    )
    (property "Footprint" "" (at 49.53 337.82 0)
      (effects (font (size 1.27 1.27)) hide)
    )
    (property "Datasheet" "" (at 49.53 337.82 0)
      (effects (font (size 1.27 1.27)) hide)
    )
    (pin "1")
    (instances
      (project "sdi-mipi-bridge"
        (path ""
          (reference "#PWR0142") (unit 1)
        )
      )
    )
  )

  (symbol (lib_id "sdi-mipi-bridge:GNDREF") (at 459.74 162.56 0) (unit 1)
    (in_bom yes) (on_board yes) (dnp no)
    (property "Reference" "#PWR0148" (at 459.74 168.91 0)
      (effects (font (size 1.27 1.27)) hide)
    )
    (property "Value" "GNDREF" (at 459.74 166.37 0)
      (effects (font (size 1.27 1.27)))
    )
    (property "Footprint" "" (at 459.74 162.56 0)
      (effects (font (size 1.27 1.27)) hide)
    )
    (property "Datasheet" "" (at 459.74 162.56 0)
      (effects (font (size 1.27 1.27)) hide)
    )
    (pin "1")
    (instances
      (project "sdi-mipi-bridge"
        (path ""
          (reference "#PWR0148") (unit 1)
        )
      )
    )
  )

  (symbol (lib_id "sdi-mipi-bridge:GNDREF") (at 41.91 337.82 0) (unit 1)
    (in_bom yes) (on_board yes) (dnp no)
    (property "Reference" "#PWR0140" (at 41.91 344.17 0)
      (effects (font (size 1.27 1.27)) hide)
    )
    (property "Value" "GNDREF" (at 42.037 342.2142 0)
      (effects (font (size 1.27 1.27)))
    )
    (property "Footprint" "" (at 41.91 337.82 0)
      (effects (font (size 1.27 1.27)) hide)
    )
    (property "Datasheet" "" (at 41.91 337.82 0)
      (effects (font (size 1.27 1.27)) hide)
    )
    (pin "1")
    (instances
      (project "sdi-mipi-bridge"
        (path ""
          (reference "#PWR0140") (unit 1)
        )
      )
    )
  )

  (symbol (lib_id "sdi-mipi-bridge:R_0R_0402") (at 384.81 163.83 0) (mirror y) (unit 1)
    (in_bom yes) (on_board yes) (dnp no)
    (property "Reference" "R105" (at 382.27 161.29 0)
      (effects (font (size 1.27 1.27)))
    )
    (property "Value" "R_0R_0402" (at 364.49 176.53 0)
      (effects (font (size 1.27 1.27) (thickness 0.15)) (justify left bottom) hide)
    )
    (property "Footprint" "sdi-mipi-bridge-footprints:R_0402_1005Metric" (at 364.49 179.07 0)
      (effects (font (size 1.27 1.27) (thickness 0.15)) (justify left bottom) hide)
    )
    (property "Datasheet" "https://industrial.panasonic.com/cdbs/www-data/pdf/RDA0000/AOA0000C301.pdf" (at 364.49 181.61 0)
      (effects (font (size 1.27 1.27) (thickness 0.15)) (justify left bottom) hide)
    )
    (property "Manufacturer" "Panasonic" (at 364.49 186.69 0)
      (effects (font (size 1.27 1.27) (thickness 0.15)) (justify left bottom) hide)
    )
    (property "MPN" "ERJ2GE0R00X" (at 364.49 184.15 0)
      (effects (font (size 1.27 1.27) (thickness 0.15)) (justify left bottom) hide)
    )
    (property "Val" "0R" (at 382.27 166.37 0)
      (effects (font (size 1.27 1.27) (thickness 0.15)))
    )
    (property "License" "Apache-2.0" (at 364.49 189.23 0)
      (effects (font (size 1.27 1.27) (thickness 0.15)) (justify left bottom) hide)
    )
    (property "Author" "Antmicro" (at 364.49 191.77 0)
      (effects (font (size 1.27 1.27) (thickness 0.15)) (justify left bottom) hide)
    )
    (property "Tolerance" "~" (at 364.49 173.99 0)
      (effects (font (size 1.27 1.27)) (justify left bottom) hide)
    )
    (property "Current" "1A" (at 364.49 194.31 0)
      (effects (font (size 1.27 1.27) (thickness 0.15)) (justify left bottom) hide)
    )
    (pin "1")
    (pin "2")
    (instances
      (project "sdi-mipi-bridge"
        (path ""
          (reference "R105") (unit 1)
        )
      )
    )
  )

  (symbol (lib_id "sdi-mipi-bridge:GNDA") (at 83.82 309.88 0) (unit 1)
    (in_bom yes) (on_board yes) (dnp no)
    (property "Reference" "#PWR0139" (at 83.82 316.23 0)
      (effects (font (size 1.27 1.27)) hide)
    )
    (property "Value" "GNDA" (at 83.947 314.2742 0)
      (effects (font (size 1.27 1.27)))
    )
    (property "Footprint" "" (at 83.82 309.88 0)
      (effects (font (size 1.27 1.27)) hide)
    )
    (property "Datasheet" "" (at 83.82 309.88 0)
      (effects (font (size 1.27 1.27)) hide)
    )
    (pin "1")
    (instances
      (project "sdi-mipi-bridge"
        (path ""
          (reference "#PWR0139") (unit 1)
        )
      )
    )
  )

  (symbol (lib_id "sdi-mipi-bridge:PWR_FLAG") (at 551.18 287.02 270) (unit 1)
    (in_bom yes) (on_board yes) (dnp no)
    (property "Reference" "#FLG0110" (at 553.085 287.02 0)
      (effects (font (size 1.27 1.27)) hide)
    )
    (property "Value" "PWR_FLAG" (at 558.8 287.02 90)
      (effects (font (size 1.27 1.27)))
    )
    (property "Footprint" "" (at 551.18 287.02 0)
      (effects (font (size 1.27 1.27)) hide)
    )
    (property "Datasheet" "" (at 551.18 287.02 0)
      (effects (font (size 1.27 1.27)) hide)
    )
    (pin "1")
    (instances
      (project "sdi-mipi-bridge"
        (path ""
          (reference "#FLG0110") (unit 1)
        )
      )
    )
  )

  (symbol (lib_id "sdi-mipi-bridge:R_10k_0402") (at 373.38 171.45 90) (unit 1)
    (in_bom yes) (on_board yes) (dnp no)
    (property "Reference" "R98" (at 375.285 167.64 90)
      (effects (font (size 1.27 1.27)) (justify right))
    )
    (property "Value" "R_10k_0402" (at 386.08 151.13 0)
      (effects (font (size 1.27 1.27) (thickness 0.15)) (justify left bottom) hide)
    )
    (property "Footprint" "sdi-mipi-bridge-footprints:R_0402_1005Metric" (at 388.62 151.13 0)
      (effects (font (size 1.27 1.27) (thickness 0.15)) (justify left bottom) hide)
    )
    (property "Datasheet" "https://www.bourns.com/docs/product-datasheets/cr.pdf" (at 391.16 151.13 0)
      (effects (font (size 1.27 1.27) (thickness 0.15)) (justify left bottom) hide)
    )
    (property "Manufacturer" "Bourns" (at 396.24 151.13 0)
      (effects (font (size 1.27 1.27) (thickness 0.15)) (justify left bottom) hide)
    )
    (property "MPN" "CR0402-FX-1002GLF" (at 393.7 151.13 0)
      (effects (font (size 1.27 1.27) (thickness 0.15)) (justify left bottom) hide)
    )
    (property "Val" "10k" (at 375.285 170.18 90)
      (effects (font (size 1.27 1.27) (thickness 0.15)) (justify right))
    )
    (property "License" "Apache-2.0" (at 398.78 151.13 0)
      (effects (font (size 1.27 1.27) (thickness 0.15)) (justify left bottom) hide)
    )
    (property "Author" "Antmicro" (at 401.32 151.13 0)
      (effects (font (size 1.27 1.27) (thickness 0.15)) (justify left bottom) hide)
    )
    (property "Tolerance" "1%" (at 383.54 151.13 0)
      (effects (font (size 1.27 1.27)) (justify left bottom) hide)
    )
    (pin "1")
    (pin "2")
    (instances
      (project "sdi-mipi-bridge"
        (path ""
          (reference "R98") (unit 1)
        )
      )
    )
  )

  (symbol (lib_id "sdi-mipi-bridge:R_10k_0402") (at 330.2 299.72 90) (unit 1)
    (in_bom yes) (on_board yes) (dnp no)
    (property "Reference" "R68" (at 330.2 288.29 0)
      (effects (font (size 1.27 1.27)) (justify right))
    )
    (property "Value" "R_10k_0402" (at 334.01 299.72 0)
      (effects (font (size 1.524 1.524)) hide)
    )
    (property "Footprint" "sdi-mipi-bridge-footprints:R_0402_1005Metric" (at 325.12 294.64 0)
      (effects (font (size 1.524 1.524)) (justify left) hide)
    )
    (property "Datasheet" "https://www.bourns.com/docs/product-datasheets/cr.pdf" (at 330.2 299.72 0)
      (effects (font (size 1.27 1.27)) hide)
    )
    (property "Manufacturer" "Bourns" (at 320.04 294.64 0)
      (effects (font (size 1.524 1.524)) (justify left) hide)
    )
    (property "MPN" "CR0402-FX-1002GLF" (at 322.58 294.64 0)
      (effects (font (size 1.524 1.524)) (justify left) hide)
    )
    (property "Val" "10k" (at 328.93 299.72 0)
      (effects (font (size 1.27 1.27)) (justify right))
    )
    (property "License" "Apache-2.0" (at 355.6 279.4 0)
      (effects (font (size 1.27 1.27) (thickness 0.15)) (justify left bottom) hide)
    )
    (property "Author" "Antmicro" (at 358.14 279.4 0)
      (effects (font (size 1.27 1.27) (thickness 0.15)) (justify left bottom) hide)
    )
    (property "Tolerance" "1%" (at 340.36 279.4 0)
      (effects (font (size 1.27 1.27)) (justify left bottom) hide)
    )
    (pin "1")
    (pin "2")
    (instances
      (project "sdi-mipi-bridge"
        (path ""
          (reference "R68") (unit 1)
        )
      )
    )
  )

  (symbol (lib_id "sdi-mipi-bridge:GNDREF") (at 237.49 233.68 0) (unit 1)
    (in_bom yes) (on_board yes) (dnp no)
    (property "Reference" "#PWR0117" (at 237.49 240.03 0)
      (effects (font (size 1.27 1.27)) hide)
    )
    (property "Value" "GNDREF" (at 237.617 238.0742 0)
      (effects (font (size 1.27 1.27)))
    )
    (property "Footprint" "" (at 237.49 233.68 0)
      (effects (font (size 1.27 1.27)) hide)
    )
    (property "Datasheet" "" (at 237.49 233.68 0)
      (effects (font (size 1.27 1.27)) hide)
    )
    (pin "1")
    (instances
      (project "sdi-mipi-bridge"
        (path ""
          (reference "#PWR0117") (unit 1)
        )
      )
    )
  )

  (symbol (lib_id "sdi-mipi-bridge:VDD") (at 90.17 132.08 0) (unit 1)
    (in_bom yes) (on_board yes) (dnp no)
    (property "Reference" "#PWR0153" (at 90.17 135.89 0)
      (effects (font (size 1.27 1.27)) hide)
    )
    (property "Value" "VDD" (at 90.17 128.27 0)
      (effects (font (size 1.27 1.27)))
    )
    (property "Footprint" "" (at 90.17 132.08 0)
      (effects (font (size 1.27 1.27)) hide)
    )
    (property "Datasheet" "" (at 90.17 132.08 0)
      (effects (font (size 1.27 1.27)) hide)
    )
    (pin "1")
    (instances
      (project "sdi-mipi-bridge"
        (path ""
          (reference "#PWR0153") (unit 1)
        )
      )
    )
  )

  (symbol (lib_id "sdi-mipi-bridge:R_10k_0402") (at 374.65 299.72 90) (unit 1)
    (in_bom yes) (on_board yes) (dnp no)
    (property "Reference" "R99" (at 374.65 288.29 0)
      (effects (font (size 1.27 1.27)) (justify right))
    )
    (property "Value" "R_10k_0402" (at 378.46 299.72 0)
      (effects (font (size 1.524 1.524)) hide)
    )
    (property "Footprint" "sdi-mipi-bridge-footprints:R_0402_1005Metric" (at 369.57 294.64 0)
      (effects (font (size 1.524 1.524)) (justify left) hide)
    )
    (property "Datasheet" "https://www.bourns.com/docs/product-datasheets/cr.pdf" (at 374.65 299.72 0)
      (effects (font (size 1.27 1.27)) hide)
    )
    (property "Manufacturer" "Bourns" (at 364.49 294.64 0)
      (effects (font (size 1.524 1.524)) (justify left) hide)
    )
    (property "MPN" "CR0402-FX-1002GLF" (at 367.03 294.64 0)
      (effects (font (size 1.524 1.524)) (justify left) hide)
    )
    (property "Val" "10k" (at 373.38 299.72 0)
      (effects (font (size 1.27 1.27)) (justify right))
    )
    (property "DNP" "DNP" (at 374.65 297.18 0)
      (effects (font (size 1.27 1.27)))
    )
    (property "License" "Apache-2.0" (at 400.05 279.4 0)
      (effects (font (size 1.27 1.27) (thickness 0.15)) (justify left bottom) hide)
    )
    (property "Author" "Antmicro" (at 402.59 279.4 0)
      (effects (font (size 1.27 1.27) (thickness 0.15)) (justify left bottom) hide)
    )
    (property "Tolerance" "1%" (at 384.81 279.4 0)
      (effects (font (size 1.27 1.27)) (justify left bottom) hide)
    )
    (pin "1")
    (pin "2")
    (instances
      (project "sdi-mipi-bridge"
        (path ""
          (reference "R99") (unit 1)
        )
      )
    )
  )

  (symbol (lib_id "sdi-mipi-bridge:GNDREF") (at 57.15 309.88 0) (unit 1)
    (in_bom yes) (on_board yes) (dnp no)
    (property "Reference" "#PWR0134" (at 57.15 316.23 0)
      (effects (font (size 1.27 1.27)) hide)
    )
    (property "Value" "GNDREF" (at 57.277 314.2742 0)
      (effects (font (size 1.27 1.27)))
    )
    (property "Footprint" "" (at 57.15 309.88 0)
      (effects (font (size 1.27 1.27)) hide)
    )
    (property "Datasheet" "" (at 57.15 309.88 0)
      (effects (font (size 1.27 1.27)) hide)
    )
    (pin "1")
    (instances
      (project "sdi-mipi-bridge"
        (path ""
          (reference "#PWR0134") (unit 1)
        )
      )
    )
  )

  (symbol (lib_id "sdi-mipi-bridge:R_10k_0402") (at 378.46 299.72 90) (unit 1)
    (in_bom yes) (on_board yes) (dnp no)
    (property "Reference" "R101" (at 378.46 287.02 0)
      (effects (font (size 1.27 1.27)) (justify right))
    )
    (property "Value" "R_10k_0402" (at 382.27 299.72 0)
      (effects (font (size 1.524 1.524)) hide)
    )
    (property "Footprint" "sdi-mipi-bridge-footprints:R_0402_1005Metric" (at 373.38 294.64 0)
      (effects (font (size 1.524 1.524)) (justify left) hide)
    )
    (property "Datasheet" "https://www.bourns.com/docs/product-datasheets/cr.pdf" (at 378.46 299.72 0)
      (effects (font (size 1.27 1.27)) hide)
    )
    (property "Manufacturer" "Bourns" (at 368.3 294.64 0)
      (effects (font (size 1.524 1.524)) (justify left) hide)
    )
    (property "MPN" "CR0402-FX-1002GLF" (at 370.84 294.64 0)
      (effects (font (size 1.524 1.524)) (justify left) hide)
    )
    (property "Val" "10k" (at 377.19 299.72 0)
      (effects (font (size 1.27 1.27)) (justify right))
    )
    (property "DNP" "DNP" (at 378.46 297.18 0)
      (effects (font (size 1.27 1.27)))
    )
    (property "License" "Apache-2.0" (at 403.86 279.4 0)
      (effects (font (size 1.27 1.27) (thickness 0.15)) (justify left bottom) hide)
    )
    (property "Author" "Antmicro" (at 406.4 279.4 0)
      (effects (font (size 1.27 1.27) (thickness 0.15)) (justify left bottom) hide)
    )
    (property "Tolerance" "1%" (at 388.62 279.4 0)
      (effects (font (size 1.27 1.27)) (justify left bottom) hide)
    )
    (pin "1")
    (pin "2")
    (instances
      (project "sdi-mipi-bridge"
        (path ""
          (reference "R101") (unit 1)
        )
      )
    )
  )

  (symbol (lib_id "sdi-mipi-bridge:GNDA") (at 373.38 171.45 0) (unit 1)
    (in_bom yes) (on_board yes) (dnp no)
    (property "Reference" "#PWR022" (at 373.38 177.8 0)
      (effects (font (size 1.27 1.27)) hide)
    )
    (property "Value" "GNDA" (at 373.507 175.8442 0)
      (effects (font (size 1.27 1.27)))
    )
    (property "Footprint" "" (at 373.38 171.45 0)
      (effects (font (size 1.27 1.27)) hide)
    )
    (property "Datasheet" "" (at 373.38 171.45 0)
      (effects (font (size 1.27 1.27)) hide)
    )
    (pin "1")
    (instances
      (project "sdi-mipi-bridge"
        (path ""
          (reference "#PWR022") (unit 1)
        )
      )
    )
  )

  (symbol (lib_id "sdi-mipi-bridge:GNDA") (at 91.44 309.88 0) (unit 1)
    (in_bom yes) (on_board yes) (dnp no)
    (property "Reference" "#PWR0138" (at 91.44 316.23 0)
      (effects (font (size 1.27 1.27)) hide)
    )
    (property "Value" "GNDA" (at 91.567 314.2742 0)
      (effects (font (size 1.27 1.27)))
    )
    (property "Footprint" "" (at 91.44 309.88 0)
      (effects (font (size 1.27 1.27)) hide)
    )
    (property "Datasheet" "" (at 91.44 309.88 0)
      (effects (font (size 1.27 1.27)) hide)
    )
    (pin "1")
    (instances
      (project "sdi-mipi-bridge"
        (path ""
          (reference "#PWR0138") (unit 1)
        )
      )
    )
  )

  (symbol (lib_id "sdi-mipi-bridge:VDD") (at 154.94 143.51 0) (unit 1)
    (in_bom yes) (on_board yes) (dnp no)
    (property "Reference" "#PWR0150" (at 154.94 147.32 0)
      (effects (font (size 1.27 1.27)) hide)
    )
    (property "Value" "VDD" (at 154.94 139.7 0)
      (effects (font (size 1.27 1.27)))
    )
    (property "Footprint" "" (at 154.94 143.51 0)
      (effects (font (size 1.27 1.27)) hide)
    )
    (property "Datasheet" "" (at 154.94 143.51 0)
      (effects (font (size 1.27 1.27)) hide)
    )
    (pin "1")
    (instances
      (project "sdi-mipi-bridge"
        (path ""
          (reference "#PWR0150") (unit 1)
        )
      )
    )
  )

  (symbol (lib_id "sdi-mipi-bridge:PWR_FLAG") (at 187.96 221.615 0) (unit 1)
    (in_bom yes) (on_board yes) (dnp no)
    (property "Reference" "#FLG0103" (at 187.96 219.71 0)
      (effects (font (size 1.27 1.27)) hide)
    )
    (property "Value" "PWR_FLAG" (at 187.96 217.805 0)
      (effects (font (size 1.27 1.27)))
    )
    (property "Footprint" "" (at 187.96 221.615 0)
      (effects (font (size 1.27 1.27)) hide)
    )
    (property "Datasheet" "" (at 187.96 221.615 0)
      (effects (font (size 1.27 1.27)) hide)
    )
    (pin "1")
    (instances
      (project "sdi-mipi-bridge"
        (path ""
          (reference "#FLG0103") (unit 1)
        )
      )
    )
  )

  (symbol (lib_id "sdi-mipi-bridge:PWR_FLAG") (at 278.765 379.73 180) (unit 1)
    (in_bom yes) (on_board yes) (dnp no)
    (property "Reference" "#FLG0109" (at 278.765 381.635 0)
      (effects (font (size 1.27 1.27)) hide)
    )
    (property "Value" "PWR_FLAG" (at 278.765 383.54 0)
      (effects (font (size 1.27 1.27)))
    )
    (property "Footprint" "" (at 278.765 379.73 0)
      (effects (font (size 1.27 1.27)) hide)
    )
    (property "Datasheet" "" (at 278.765 379.73 0)
      (effects (font (size 1.27 1.27)) hide)
    )
    (pin "1")
    (instances
      (project "sdi-mipi-bridge"
        (path ""
          (reference "#FLG0109") (unit 1)
        )
      )
    )
  )

  (symbol (lib_id "sdi-mipi-bridge:R_10k_0402") (at 337.82 299.72 90) (unit 1)
    (in_bom yes) (on_board yes) (dnp no)
    (property "Reference" "R78" (at 337.82 288.29 0)
      (effects (font (size 1.27 1.27)) (justify right))
    )
    (property "Value" "R_10k_0402" (at 341.63 299.72 0)
      (effects (font (size 1.524 1.524)) hide)
    )
    (property "Footprint" "sdi-mipi-bridge-footprints:R_0402_1005Metric" (at 332.74 294.64 0)
      (effects (font (size 1.524 1.524)) (justify left) hide)
    )
    (property "Datasheet" "https://www.bourns.com/docs/product-datasheets/cr.pdf" (at 337.82 299.72 0)
      (effects (font (size 1.27 1.27)) hide)
    )
    (property "Manufacturer" "Bourns" (at 327.66 294.64 0)
      (effects (font (size 1.524 1.524)) (justify left) hide)
    )
    (property "MPN" "CR0402-FX-1002GLF" (at 330.2 294.64 0)
      (effects (font (size 1.524 1.524)) (justify left) hide)
    )
    (property "Val" "10k" (at 336.55 299.72 0)
      (effects (font (size 1.27 1.27)) (justify right))
    )
    (property "License" "Apache-2.0" (at 363.22 279.4 0)
      (effects (font (size 1.27 1.27) (thickness 0.15)) (justify left bottom) hide)
    )
    (property "Author" "Antmicro" (at 365.76 279.4 0)
      (effects (font (size 1.27 1.27) (thickness 0.15)) (justify left bottom) hide)
    )
    (property "Tolerance" "1%" (at 347.98 279.4 0)
      (effects (font (size 1.27 1.27)) (justify left bottom) hide)
    )
    (pin "1")
    (pin "2")
    (instances
      (project "sdi-mipi-bridge"
        (path ""
          (reference "R78") (unit 1)
        )
      )
    )
  )

  (symbol (lib_id "sdi-mipi-bridge:GS2971A") (at 63.5 44.45 0) (unit 1)
    (in_bom yes) (on_board yes) (dnp no) (fields_autoplaced)
    (property "Reference" "U2" (at 76.835 37.465 0)
      (effects (font (size 1.27 1.27) (thickness 0.15)))
    )
    (property "Value" "GS2971A" (at 76.835 40.005 0)
      (effects (font (size 1.27 1.27) (thickness 0.15)))
    )
    (property "Footprint" "sdi-mipi-bridge-footprints:BGA100_11x11mm_SEMTECH" (at 119.38 52.07 0)
      (effects (font (size 1.27 1.27) (thickness 0.15)) (justify left bottom) hide)
    )
    (property "Datasheet" "https://semtech.my.salesforce.com/sfc/p/#E0000000JelG/a/44000000MD3i/kpmMkrmUWgHlbCOwdLzVohMm1SDPoVH85guEGK.KXTc" (at 119.38 54.61 0)
      (effects (font (size 1.27 1.27) (thickness 0.15)) (justify left bottom) hide)
    )
    (property "MPN" "GS2971A" (at 119.38 57.15 0)
      (effects (font (size 1.27 1.27) (thickness 0.15)) (justify left bottom) hide)
    )
    (property "Manufacturer" "Semtech" (at 119.38 59.69 0)
      (effects (font (size 1.27 1.27) (thickness 0.15)) (justify left bottom) hide)
    )
    (property "Author" "Antmicro" (at 119.38 62.23 0)
      (effects (font (size 1.27 1.27) (thickness 0.15)) (justify left bottom) hide)
    )
    (property "License" "Apache-2.0" (at 119.38 64.77 0)
      (effects (font (size 1.27 1.27) (thickness 0.15)) (justify left bottom) hide)
    )
    (pin "A10")
    (pin "A5")
    (pin "A6")
    (pin "A8")
    (pin "A9")
    (pin "B10")
    (pin "B5")
    (pin "B6")
    (pin "B8")
    (pin "B9")
    (pin "C10")
    (pin "C5")
    (pin "C6")
    (pin "C8")
    (pin "C9")
    (pin "E10")
    (pin "E9")
    (pin "F10")
    (pin "F9")
    (pin "H10")
    (pin "H4")
    (pin "H9")
    (pin "J1")
    (pin "J10")
    (pin "J3")
    (pin "J4")
    (pin "J5")
    (pin "J8")
    (pin "J9")
    (pin "K1")
    (pin "K10")
    (pin "K3")
    (pin "K4")
    (pin "K5")
    (pin "K8")
    (pin "K9")
    (pin "A1")
    (pin "A2")
    (pin "A3")
    (pin "B3")
    (pin "C1")
    (pin "C7")
    (pin "D1")
    (pin "D7")
    (pin "D8")
    (pin "E7")
    (pin "E8")
    (pin "F1")
    (pin "F2")
    (pin "F7")
    (pin "F8")
    (pin "G1")
    (pin "G3")
    (pin "G7")
    (pin "G8")
    (pin "H3")
    (pin "H5")
    (pin "H6")
    (pin "H7")
    (pin "H8")
    (pin "J2")
    (pin "J6")
    (pin "K2")
    (pin "K6")
    (pin "A4")
    (pin "A7")
    (pin "B1")
    (pin "B2")
    (pin "B4")
    (pin "B7")
    (pin "C2")
    (pin "C3")
    (pin "C4")
    (pin "D10")
    (pin "D2")
    (pin "D3")
    (pin "D4")
    (pin "D5")
    (pin "D6")
    (pin "D9")
    (pin "E1")
    (pin "E2")
    (pin "E3")
    (pin "E4")
    (pin "E5")
    (pin "E6")
    (pin "F3")
    (pin "F4")
    (pin "F5")
    (pin "F6")
    (pin "G10")
    (pin "G2")
    (pin "G4")
    (pin "G5")
    (pin "G6")
    (pin "G9")
    (pin "H1")
    (pin "H2")
    (pin "J7")
    (pin "K7")
    (instances
      (project "sdi-mipi-bridge"
        (path ""
          (reference "U2") (unit 1)
        )
      )
    )
  )

  (symbol (lib_id "sdi-mipi-bridge:SW_SPST_KMR211NGLFS") (at 360.68 383.54 90) (unit 1)
    (in_bom yes) (on_board yes) (dnp no) (fields_autoplaced)
    (property "Reference" "SW1" (at 364.49 377.1899 90)
      (effects (font (size 1.27 1.27) (thickness 0.15)) (justify right))
    )
    (property "Value" "SW_SPST_KMR211NGLFS" (at 364.49 379.7299 90)
      (effects (font (size 1.27 1.27) (thickness 0.15)) (justify right))
    )
    (property "Footprint" "sdi-mipi-bridge-footprints:SW_SPST_4.2x2.8" (at 368.3 358.14 0)
      (effects (font (size 1.27 1.27) (thickness 0.15)) (justify left bottom) hide)
    )
    (property "Datasheet" "http://www.farnell.com/datasheets/2631211.pdf" (at 370.84 358.14 0)
      (effects (font (size 1.27 1.27) (thickness 0.15)) (justify left bottom) hide)
    )
    (property "MPN" "KMR211NGLFS" (at 373.38 358.14 0)
      (effects (font (size 1.27 1.27) (thickness 0.15)) (justify left bottom) hide)
    )
    (property "Manufacturer" "C&K" (at 375.92 358.14 0)
      (effects (font (size 1.27 1.27) (thickness 0.15)) (justify left bottom) hide)
    )
    (property "Author" "Antmicro" (at 378.46 358.14 0)
      (effects (font (size 1.27 1.27) (thickness 0.15)) (justify left bottom) hide)
    )
    (property "License" "Apache-2.0" (at 381 358.14 0)
      (effects (font (size 1.27 1.27) (thickness 0.15)) (justify left bottom) hide)
    )
    (pin "1")
    (pin "2")
    (pin "3")
    (pin "4")
    (instances
      (project "sdi-mipi-bridge"
        (path ""
          (reference "SW1") (unit 1)
        )
      )
    )
  )

  (symbol (lib_id "sdi-mipi-bridge:R_10k_0402") (at 389.89 322.58 90) (unit 1)
    (in_bom yes) (on_board yes) (dnp no)
    (property "Reference" "R109" (at 389.89 327.66 0)
      (effects (font (size 1.27 1.27)) (justify right))
    )
    (property "Value" "R_10k_0402" (at 393.7 322.58 0)
      (effects (font (size 1.524 1.524)) hide)
    )
    (property "Footprint" "sdi-mipi-bridge-footprints:R_0402_1005Metric" (at 384.81 317.5 0)
      (effects (font (size 1.524 1.524)) (justify left) hide)
    )
    (property "Datasheet" "https://www.bourns.com/docs/product-datasheets/cr.pdf" (at 389.89 322.58 0)
      (effects (font (size 1.27 1.27)) hide)
    )
    (property "Manufacturer" "Bourns" (at 379.73 317.5 0)
      (effects (font (size 1.524 1.524)) (justify left) hide)
    )
    (property "MPN" "CR0402-FX-1002GLF" (at 382.27 317.5 0)
      (effects (font (size 1.524 1.524)) (justify left) hide)
    )
    (property "Val" "10k" (at 388.62 322.58 0)
      (effects (font (size 1.27 1.27)) (justify right))
    )
    (property "License" "Apache-2.0" (at 415.29 302.26 0)
      (effects (font (size 1.27 1.27) (thickness 0.15)) (justify left bottom) hide)
    )
    (property "Author" "Antmicro" (at 417.83 302.26 0)
      (effects (font (size 1.27 1.27) (thickness 0.15)) (justify left bottom) hide)
    )
    (property "Tolerance" "1%" (at 400.05 302.26 0)
      (effects (font (size 1.27 1.27)) (justify left bottom) hide)
    )
    (pin "1")
    (pin "2")
    (instances
      (project "sdi-mipi-bridge"
        (path ""
          (reference "R109") (unit 1)
        )
      )
    )
  )

  (symbol (lib_id "sdi-mipi-bridge:R_10k_0402") (at 378.46 322.58 90) (unit 1)
    (in_bom yes) (on_board yes) (dnp no)
    (property "Reference" "R102" (at 378.46 327.66 0)
      (effects (font (size 1.27 1.27)) (justify right))
    )
    (property "Value" "R_10k_0402" (at 382.27 322.58 0)
      (effects (font (size 1.524 1.524)) hide)
    )
    (property "Footprint" "sdi-mipi-bridge-footprints:R_0402_1005Metric" (at 373.38 317.5 0)
      (effects (font (size 1.524 1.524)) (justify left) hide)
    )
    (property "Datasheet" "https://www.bourns.com/docs/product-datasheets/cr.pdf" (at 378.46 322.58 0)
      (effects (font (size 1.27 1.27)) hide)
    )
    (property "Manufacturer" "Bourns" (at 368.3 317.5 0)
      (effects (font (size 1.524 1.524)) (justify left) hide)
    )
    (property "MPN" "CR0402-FX-1002GLF" (at 370.84 317.5 0)
      (effects (font (size 1.524 1.524)) (justify left) hide)
    )
    (property "Val" "10k" (at 377.19 322.58 0)
      (effects (font (size 1.27 1.27)) (justify right))
    )
    (property "License" "Apache-2.0" (at 403.86 302.26 0)
      (effects (font (size 1.27 1.27) (thickness 0.15)) (justify left bottom) hide)
    )
    (property "Author" "Antmicro" (at 406.4 302.26 0)
      (effects (font (size 1.27 1.27) (thickness 0.15)) (justify left bottom) hide)
    )
    (property "Tolerance" "1%" (at 388.62 302.26 0)
      (effects (font (size 1.27 1.27)) (justify left bottom) hide)
    )
    (pin "1")
    (pin "2")
    (instances
      (project "sdi-mipi-bridge"
        (path ""
          (reference "R102") (unit 1)
        )
      )
    )
  )

  (symbol (lib_id "sdi-mipi-bridge:GNDA") (at 368.3 328.93 0) (unit 1)
    (in_bom yes) (on_board yes) (dnp no)
    (property "Reference" "#PWR018" (at 368.3 335.28 0)
      (effects (font (size 1.27 1.27)) hide)
    )
    (property "Value" "GNDA" (at 368.427 333.3242 0)
      (effects (font (size 1.27 1.27)))
    )
    (property "Footprint" "" (at 368.3 328.93 0)
      (effects (font (size 1.27 1.27)) hide)
    )
    (property "Datasheet" "" (at 368.3 328.93 0)
      (effects (font (size 1.27 1.27)) hide)
    )
    (pin "1")
    (instances
      (project "sdi-mipi-bridge"
        (path ""
          (reference "#PWR018") (unit 1)
        )
      )
    )
  )

  (symbol (lib_id "sdi-mipi-bridge:R_10k_0402") (at 386.08 299.72 90) (unit 1)
    (in_bom yes) (on_board yes) (dnp no)
    (property "Reference" "R106" (at 386.08 287.02 0)
      (effects (font (size 1.27 1.27)) (justify right))
    )
    (property "Value" "R_10k_0402" (at 389.89 299.72 0)
      (effects (font (size 1.524 1.524)) hide)
    )
    (property "Footprint" "sdi-mipi-bridge-footprints:R_0402_1005Metric" (at 381 294.64 0)
      (effects (font (size 1.524 1.524)) (justify left) hide)
    )
    (property "Datasheet" "https://www.bourns.com/docs/product-datasheets/cr.pdf" (at 386.08 299.72 0)
      (effects (font (size 1.27 1.27)) hide)
    )
    (property "Manufacturer" "Bourns" (at 375.92 294.64 0)
      (effects (font (size 1.524 1.524)) (justify left) hide)
    )
    (property "MPN" "CR0402-FX-1002GLF" (at 378.46 294.64 0)
      (effects (font (size 1.524 1.524)) (justify left) hide)
    )
    (property "Val" "10k" (at 384.81 299.72 0)
      (effects (font (size 1.27 1.27)) (justify right))
    )
    (property "DNP" "DNP" (at 386.08 297.18 0)
      (effects (font (size 1.27 1.27)))
    )
    (property "License" "Apache-2.0" (at 411.48 279.4 0)
      (effects (font (size 1.27 1.27) (thickness 0.15)) (justify left bottom) hide)
    )
    (property "Author" "Antmicro" (at 414.02 279.4 0)
      (effects (font (size 1.27 1.27) (thickness 0.15)) (justify left bottom) hide)
    )
    (property "Tolerance" "1%" (at 396.24 279.4 0)
      (effects (font (size 1.27 1.27)) (justify left bottom) hide)
    )
    (pin "1")
    (pin "2")
    (instances
      (project "sdi-mipi-bridge"
        (path ""
          (reference "R106") (unit 1)
        )
      )
    )
  )

  (symbol (lib_id "sdi-mipi-bridge:GNDA") (at 91.44 337.82 0) (unit 1)
    (in_bom yes) (on_board yes) (dnp no)
    (property "Reference" "#PWR0137" (at 91.44 344.17 0)
      (effects (font (size 1.27 1.27)) hide)
    )
    (property "Value" "GNDA" (at 91.567 342.2142 0)
      (effects (font (size 1.27 1.27)))
    )
    (property "Footprint" "" (at 91.44 337.82 0)
      (effects (font (size 1.27 1.27)) hide)
    )
    (property "Datasheet" "" (at 91.44 337.82 0)
      (effects (font (size 1.27 1.27)) hide)
    )
    (pin "1")
    (instances
      (project "sdi-mipi-bridge"
        (path ""
          (reference "#PWR0137") (unit 1)
        )
      )
    )
  )

  (symbol (lib_id "sdi-mipi-bridge:R_10k_0402") (at 341.63 299.72 90) (unit 1)
    (in_bom yes) (on_board yes) (dnp no)
    (property "Reference" "R80" (at 341.63 288.29 0)
      (effects (font (size 1.27 1.27)) (justify right))
    )
    (property "Value" "R_10k_0402" (at 345.44 299.72 0)
      (effects (font (size 1.524 1.524)) hide)
    )
    (property "Footprint" "sdi-mipi-bridge-footprints:R_0402_1005Metric" (at 336.55 294.64 0)
      (effects (font (size 1.524 1.524)) (justify left) hide)
    )
    (property "Datasheet" "https://www.bourns.com/docs/product-datasheets/cr.pdf" (at 341.63 299.72 0)
      (effects (font (size 1.27 1.27)) hide)
    )
    (property "Manufacturer" "Bourns" (at 331.47 294.64 0)
      (effects (font (size 1.524 1.524)) (justify left) hide)
    )
    (property "MPN" "CR0402-FX-1002GLF" (at 334.01 294.64 0)
      (effects (font (size 1.524 1.524)) (justify left) hide)
    )
    (property "Val" "10k" (at 340.36 299.72 0)
      (effects (font (size 1.27 1.27)) (justify right))
    )
    (property "DNP" "DNP" (at 341.63 297.18 0)
      (effects (font (size 1.27 1.27)))
    )
    (property "License" "Apache-2.0" (at 367.03 279.4 0)
      (effects (font (size 1.27 1.27) (thickness 0.15)) (justify left bottom) hide)
    )
    (property "Author" "Antmicro" (at 369.57 279.4 0)
      (effects (font (size 1.27 1.27) (thickness 0.15)) (justify left bottom) hide)
    )
    (property "Tolerance" "1%" (at 351.79 279.4 0)
      (effects (font (size 1.27 1.27)) (justify left bottom) hide)
    )
    (pin "1")
    (pin "2")
    (instances
      (project "sdi-mipi-bridge"
        (path ""
          (reference "R80") (unit 1)
        )
      )
    )
  )

  (symbol (lib_id "sdi-mipi-bridge:GNDREF") (at 153.67 271.78 0) (unit 1)
    (in_bom yes) (on_board yes) (dnp no)
    (property "Reference" "#PWR0104" (at 153.67 278.13 0)
      (effects (font (size 1.27 1.27)) hide)
    )
    (property "Value" "GNDREF" (at 153.67 275.59 0)
      (effects (font (size 1.27 1.27)))
    )
    (property "Footprint" "" (at 153.67 271.78 0)
      (effects (font (size 1.27 1.27)) hide)
    )
    (property "Datasheet" "" (at 153.67 271.78 0)
      (effects (font (size 1.27 1.27)) hide)
    )
    (pin "1")
    (instances
      (project "sdi-mipi-bridge"
        (path ""
          (reference "#PWR0104") (unit 1)
        )
      )
    )
  )

  (symbol (lib_id "sdi-mipi-bridge:PWR_FLAG") (at 334.645 140.97 0) (unit 1)
    (in_bom yes) (on_board yes) (dnp no)
    (property "Reference" "#FLG0112" (at 334.645 139.065 0)
      (effects (font (size 1.27 1.27)) hide)
    )
    (property "Value" "PWR_FLAG" (at 334.645 137.16 0)
      (effects (font (size 1.27 1.27)))
    )
    (property "Footprint" "" (at 334.645 140.97 0)
      (effects (font (size 1.27 1.27)) hide)
    )
    (property "Datasheet" "" (at 334.645 140.97 0)
      (effects (font (size 1.27 1.27)) hide)
    )
    (pin "1")
    (instances
      (project "sdi-mipi-bridge"
        (path ""
          (reference "#FLG0112") (unit 1)
        )
      )
    )
  )

  (symbol (lib_id "sdi-mipi-bridge:PWR_FLAG") (at 278.765 370.84 0) (unit 1)
    (in_bom yes) (on_board yes) (dnp no)
    (property "Reference" "#FLG0108" (at 278.765 368.935 0)
      (effects (font (size 1.27 1.27)) hide)
    )
    (property "Value" "PWR_FLAG" (at 278.765 367.03 0)
      (effects (font (size 1.27 1.27)))
    )
    (property "Footprint" "" (at 278.765 370.84 0)
      (effects (font (size 1.27 1.27)) hide)
    )
    (property "Datasheet" "" (at 278.765 370.84 0)
      (effects (font (size 1.27 1.27)) hide)
    )
    (pin "1")
    (instances
      (project "sdi-mipi-bridge"
        (path ""
          (reference "#FLG0108") (unit 1)
        )
      )
    )
  )

  (symbol (lib_id "sdi-mipi-bridge:PWR_FLAG") (at 165.1 346.075 0) (unit 1)
    (in_bom yes) (on_board yes) (dnp no)
    (property "Reference" "#FLG0111" (at 165.1 344.17 0)
      (effects (font (size 1.27 1.27)) hide)
    )
    (property "Value" "PWR_FLAG" (at 165.1 342.265 0)
      (effects (font (size 1.27 1.27)))
    )
    (property "Footprint" "" (at 165.1 346.075 0)
      (effects (font (size 1.27 1.27)) hide)
    )
    (property "Datasheet" "" (at 165.1 346.075 0)
      (effects (font (size 1.27 1.27)) hide)
    )
    (pin "1")
    (instances
      (project "sdi-mipi-bridge"
        (path ""
          (reference "#FLG0111") (unit 1)
        )
      )
    )
  )

  (symbol (lib_id "sdi-mipi-bridge:GNDREF") (at 250.19 306.07 0) (unit 1)
    (in_bom yes) (on_board yes) (dnp no)
    (property "Reference" "#PWR0108" (at 250.19 312.42 0)
      (effects (font (size 1.27 1.27)) hide)
    )
    (property "Value" "GNDREF" (at 250.317 310.4642 0)
      (effects (font (size 1.27 1.27)))
    )
    (property "Footprint" "" (at 250.19 306.07 0)
      (effects (font (size 1.27 1.27)) hide)
    )
    (property "Datasheet" "" (at 250.19 306.07 0)
      (effects (font (size 1.27 1.27)) hide)
    )
    (pin "1")
    (instances
      (project "sdi-mipi-bridge"
        (path ""
          (reference "#PWR0108") (unit 1)
        )
      )
    )
  )

  (symbol (lib_id "sdi-mipi-bridge:R_10k_0402") (at 389.89 299.72 90) (unit 1)
    (in_bom yes) (on_board yes) (dnp no)
    (property "Reference" "R108" (at 389.89 287.02 0)
      (effects (font (size 1.27 1.27)) (justify right))
    )
    (property "Value" "R_10k_0402" (at 393.7 299.72 0)
      (effects (font (size 1.524 1.524)) hide)
    )
    (property "Footprint" "sdi-mipi-bridge-footprints:R_0402_1005Metric" (at 384.81 294.64 0)
      (effects (font (size 1.524 1.524)) (justify left) hide)
    )
    (property "Datasheet" "https://www.bourns.com/docs/product-datasheets/cr.pdf" (at 389.89 299.72 0)
      (effects (font (size 1.27 1.27)) hide)
    )
    (property "Manufacturer" "Bourns" (at 379.73 294.64 0)
      (effects (font (size 1.524 1.524)) (justify left) hide)
    )
    (property "MPN" "CR0402-FX-1002GLF" (at 382.27 294.64 0)
      (effects (font (size 1.524 1.524)) (justify left) hide)
    )
    (property "Val" "10k" (at 388.62 299.72 0)
      (effects (font (size 1.27 1.27)) (justify right))
    )
    (property "DNP" "DNP" (at 389.89 297.18 0)
      (effects (font (size 1.27 1.27)))
    )
    (property "License" "Apache-2.0" (at 415.29 279.4 0)
      (effects (font (size 1.27 1.27) (thickness 0.15)) (justify left bottom) hide)
    )
    (property "Author" "Antmicro" (at 417.83 279.4 0)
      (effects (font (size 1.27 1.27) (thickness 0.15)) (justify left bottom) hide)
    )
    (property "Tolerance" "1%" (at 400.05 279.4 0)
      (effects (font (size 1.27 1.27)) (justify left bottom) hide)
    )
    (pin "1")
    (pin "2")
    (instances
      (project "sdi-mipi-bridge"
        (path ""
          (reference "R108") (unit 1)
        )
      )
    )
  )

  (symbol (lib_id "sdi-mipi-bridge:PWR_FLAG") (at 251.46 330.835 0) (unit 1)
    (in_bom yes) (on_board yes) (dnp no)
    (property "Reference" "#FLG0114" (at 251.46 328.93 0)
      (effects (font (size 1.27 1.27)) hide)
    )
    (property "Value" "PWR_FLAG" (at 251.46 327.025 0)
      (effects (font (size 1.27 1.27)))
    )
    (property "Footprint" "" (at 251.46 330.835 0)
      (effects (font (size 1.27 1.27)) hide)
    )
    (property "Datasheet" "" (at 251.46 330.835 0)
      (effects (font (size 1.27 1.27)) hide)
    )
    (pin "1")
    (instances
      (project "sdi-mipi-bridge"
        (path ""
          (reference "#FLG0114") (unit 1)
        )
      )
    )
  )

  (symbol (lib_id "sdi-mipi-bridge:PWR_FLAG") (at 419.1 148.59 0) (unit 1)
    (in_bom yes) (on_board yes) (dnp no)
    (property "Reference" "#FLG0107" (at 419.1 146.685 0)
      (effects (font (size 1.27 1.27)) hide)
    )
    (property "Value" "PWR_FLAG" (at 419.1 144.145 0)
      (effects (font (size 1.27 1.27)))
    )
    (property "Footprint" "" (at 419.1 148.59 0)
      (effects (font (size 1.27 1.27)) hide)
    )
    (property "Datasheet" "" (at 419.1 148.59 0)
      (effects (font (size 1.27 1.27)) hide)
    )
    (pin "1")
    (instances
      (project "sdi-mipi-bridge"
        (path ""
          (reference "#FLG0107") (unit 1)
        )
      )
    )
  )

  (symbol (lib_id "sdi-mipi-bridge:R_10k_0402") (at 393.7 322.58 90) (unit 1)
    (in_bom yes) (on_board yes) (dnp no)
    (property "Reference" "R111" (at 393.7 327.66 0)
      (effects (font (size 1.27 1.27)) (justify right))
    )
    (property "Value" "R_10k_0402" (at 397.51 322.58 0)
      (effects (font (size 1.524 1.524)) hide)
    )
    (property "Footprint" "sdi-mipi-bridge-footprints:R_0402_1005Metric" (at 388.62 317.5 0)
      (effects (font (size 1.524 1.524)) (justify left) hide)
    )
    (property "Datasheet" "https://www.bourns.com/docs/product-datasheets/cr.pdf" (at 393.7 322.58 0)
      (effects (font (size 1.27 1.27)) hide)
    )
    (property "Manufacturer" "Bourns" (at 383.54 317.5 0)
      (effects (font (size 1.524 1.524)) (justify left) hide)
    )
    (property "MPN" "CR0402-FX-1002GLF" (at 386.08 317.5 0)
      (effects (font (size 1.524 1.524)) (justify left) hide)
    )
    (property "Val" "10k" (at 392.43 322.58 0)
      (effects (font (size 1.27 1.27)) (justify right))
    )
    (property "License" "Apache-2.0" (at 419.1 302.26 0)
      (effects (font (size 1.27 1.27) (thickness 0.15)) (justify left bottom) hide)
    )
    (property "Author" "Antmicro" (at 421.64 302.26 0)
      (effects (font (size 1.27 1.27) (thickness 0.15)) (justify left bottom) hide)
    )
    (property "Tolerance" "1%" (at 403.86 302.26 0)
      (effects (font (size 1.27 1.27)) (justify left bottom) hide)
    )
    (pin "1")
    (pin "2")
    (instances
      (project "sdi-mipi-bridge"
        (path ""
          (reference "R111") (unit 1)
        )
      )
    )
  )

  (symbol (lib_id "sdi-mipi-bridge:R_10k_0402") (at 334.01 322.58 90) (unit 1)
    (in_bom yes) (on_board yes) (dnp no)
    (property "Reference" "R77" (at 334.01 327.66 0)
      (effects (font (size 1.27 1.27)) (justify right))
    )
    (property "Value" "R_10k_0402" (at 337.82 322.58 0)
      (effects (font (size 1.524 1.524)) hide)
    )
    (property "Footprint" "sdi-mipi-bridge-footprints:R_0402_1005Metric" (at 328.93 317.5 0)
      (effects (font (size 1.524 1.524)) (justify left) hide)
    )
    (property "Datasheet" "https://www.bourns.com/docs/product-datasheets/cr.pdf" (at 334.01 322.58 0)
      (effects (font (size 1.27 1.27)) hide)
    )
    (property "Manufacturer" "Bourns" (at 323.85 317.5 0)
      (effects (font (size 1.524 1.524)) (justify left) hide)
    )
    (property "MPN" "CR0402-FX-1002GLF" (at 326.39 317.5 0)
      (effects (font (size 1.524 1.524)) (justify left) hide)
    )
    (property "Val" "10k" (at 332.74 322.58 0)
      (effects (font (size 1.27 1.27)) (justify right))
    )
    (property "DNP" "DNP" (at 334.01 320.04 0)
      (effects (font (size 1.27 1.27)))
    )
    (property "License" "Apache-2.0" (at 359.41 302.26 0)
      (effects (font (size 1.27 1.27) (thickness 0.15)) (justify left bottom) hide)
    )
    (property "Author" "Antmicro" (at 361.95 302.26 0)
      (effects (font (size 1.27 1.27) (thickness 0.15)) (justify left bottom) hide)
    )
    (property "Tolerance" "1%" (at 344.17 302.26 0)
      (effects (font (size 1.27 1.27)) (justify left bottom) hide)
    )
    (pin "1")
    (pin "2")
    (instances
      (project "sdi-mipi-bridge"
        (path ""
          (reference "R77") (unit 1)
        )
      )
    )
  )

  (symbol (lib_id "sdi-mipi-bridge:VPP") (at 176.53 262.89 0) (unit 1)
    (in_bom yes) (on_board yes) (dnp no)
    (property "Reference" "#PWR0154" (at 176.53 266.7 0)
      (effects (font (size 1.27 1.27)) hide)
    )
    (property "Value" "VPP" (at 176.53 259.08 0)
      (effects (font (size 1.27 1.27)))
    )
    (property "Footprint" "" (at 176.53 262.89 0)
      (effects (font (size 1.27 1.27)) hide)
    )
    (property "Datasheet" "" (at 176.53 262.89 0)
      (effects (font (size 1.27 1.27)) hide)
    )
    (pin "1")
    (instances
      (project "sdi-mipi-bridge"
        (path ""
          (reference "#PWR0154") (unit 1)
        )
      )
    )
  )

  (symbol (lib_id "sdi-mipi-bridge:GNDREF") (at 238.76 306.07 0) (unit 1)
    (in_bom yes) (on_board yes) (dnp no)
    (property "Reference" "#PWR0105" (at 238.76 312.42 0)
      (effects (font (size 1.27 1.27)) hide)
    )
    (property "Value" "GNDREF" (at 238.887 310.4642 0)
      (effects (font (size 1.27 1.27)))
    )
    (property "Footprint" "" (at 238.76 306.07 0)
      (effects (font (size 1.27 1.27)) hide)
    )
    (property "Datasheet" "" (at 238.76 306.07 0)
      (effects (font (size 1.27 1.27)) hide)
    )
    (pin "1")
    (instances
      (project "sdi-mipi-bridge"
        (path ""
          (reference "#PWR0105") (unit 1)
        )
      )
    )
  )

  (symbol (lib_id "sdi-mipi-bridge:R_10k_0402") (at 326.39 299.72 90) (unit 1)
    (in_bom yes) (on_board yes) (dnp no)
    (property "Reference" "R65" (at 326.39 288.29 0)
      (effects (font (size 1.27 1.27)) (justify right))
    )
    (property "Value" "R_10k_0402" (at 330.2 299.72 0)
      (effects (font (size 1.524 1.524)) hide)
    )
    (property "Footprint" "sdi-mipi-bridge-footprints:R_0402_1005Metric" (at 321.31 294.64 0)
      (effects (font (size 1.524 1.524)) (justify left) hide)
    )
    (property "Datasheet" "https://www.bourns.com/docs/product-datasheets/cr.pdf" (at 326.39 299.72 0)
      (effects (font (size 1.27 1.27)) hide)
    )
    (property "Manufacturer" "Bourns" (at 316.23 294.64 0)
      (effects (font (size 1.524 1.524)) (justify left) hide)
    )
    (property "MPN" "CR0402-FX-1002GLF" (at 318.77 294.64 0)
      (effects (font (size 1.524 1.524)) (justify left) hide)
    )
    (property "Val" "10k" (at 325.12 299.72 0)
      (effects (font (size 1.27 1.27)) (justify right))
    )
    (property "License" "Apache-2.0" (at 351.79 279.4 0)
      (effects (font (size 1.27 1.27) (thickness 0.15)) (justify left bottom) hide)
    )
    (property "Author" "Antmicro" (at 354.33 279.4 0)
      (effects (font (size 1.27 1.27) (thickness 0.15)) (justify left bottom) hide)
    )
    (property "Tolerance" "1%" (at 336.55 279.4 0)
      (effects (font (size 1.27 1.27)) (justify left bottom) hide)
    )
    (pin "1")
    (pin "2")
    (instances
      (project "sdi-mipi-bridge"
        (path ""
          (reference "R65") (unit 1)
        )
      )
    )
  )

  (symbol (lib_id "sdi-mipi-bridge:PWR_FLAG") (at 271.78 265.43 0) (unit 1)
    (in_bom yes) (on_board yes) (dnp no)
    (property "Reference" "#FLG0106" (at 271.78 263.525 0)
      (effects (font (size 1.27 1.27)) hide)
    )
    (property "Value" "PWR_FLAG" (at 271.78 261.62 0)
      (effects (font (size 1.27 1.27)))
    )
    (property "Footprint" "" (at 271.78 265.43 0)
      (effects (font (size 1.27 1.27)) hide)
    )
    (property "Datasheet" "" (at 271.78 265.43 0)
      (effects (font (size 1.27 1.27)) hide)
    )
    (pin "1")
    (instances
      (project "sdi-mipi-bridge"
        (path ""
          (reference "#FLG0106") (unit 1)
        )
      )
    )
  )

  (symbol (lib_id "sdi-mipi-bridge:VPP") (at 269.24 59.69 0) (unit 1)
    (in_bom yes) (on_board yes) (dnp no)
    (property "Reference" "#PWR0155" (at 269.24 63.5 0)
      (effects (font (size 1.27 1.27)) hide)
    )
    (property "Value" "VPP" (at 269.24 55.88 0)
      (effects (font (size 1.27 1.27)))
    )
    (property "Footprint" "" (at 269.24 59.69 0)
      (effects (font (size 1.27 1.27)) hide)
    )
    (property "Datasheet" "" (at 269.24 59.69 0)
      (effects (font (size 1.27 1.27)) hide)
    )
    (pin "1")
    (instances
      (project "sdi-mipi-bridge"
        (path ""
          (reference "#PWR0155") (unit 1)
        )
      )
    )
  )

  (symbol (lib_id "sdi-mipi-bridge:GNDREF") (at 274.32 233.68 0) (unit 1)
    (in_bom yes) (on_board yes) (dnp no)
    (property "Reference" "#PWR0147" (at 274.32 240.03 0)
      (effects (font (size 1.27 1.27)) hide)
    )
    (property "Value" "GNDREF" (at 274.447 238.0742 0)
      (effects (font (size 1.27 1.27)))
    )
    (property "Footprint" "" (at 274.32 233.68 0)
      (effects (font (size 1.27 1.27)) hide)
    )
    (property "Datasheet" "" (at 274.32 233.68 0)
      (effects (font (size 1.27 1.27)) hide)
    )
    (pin "1")
    (instances
      (project "sdi-mipi-bridge"
        (path ""
          (reference "#PWR0147") (unit 1)
        )
      )
    )
  )

  (symbol (lib_id "sdi-mipi-bridge:GNDREF") (at 256.54 233.68 0) (unit 1)
    (in_bom yes) (on_board yes) (dnp no)
    (property "Reference" "#PWR0132" (at 256.54 240.03 0)
      (effects (font (size 1.27 1.27)) hide)
    )
    (property "Value" "GNDREF" (at 256.667 238.0742 0)
      (effects (font (size 1.27 1.27)))
    )
    (property "Footprint" "" (at 256.54 233.68 0)
      (effects (font (size 1.27 1.27)) hide)
    )
    (property "Datasheet" "" (at 256.54 233.68 0)
      (effects (font (size 1.27 1.27)) hide)
    )
    (pin "1")
    (instances
      (project "sdi-mipi-bridge"
        (path ""
          (reference "#PWR0132") (unit 1)
        )
      )
    )
  )

  (symbol (lib_id "sdi-mipi-bridge:GNDREF") (at 41.91 309.88 0) (unit 1)
    (in_bom yes) (on_board yes) (dnp no)
    (property "Reference" "#PWR0135" (at 41.91 316.23 0)
      (effects (font (size 1.27 1.27)) hide)
    )
    (property "Value" "GNDREF" (at 42.037 314.2742 0)
      (effects (font (size 1.27 1.27)))
    )
    (property "Footprint" "" (at 41.91 309.88 0)
      (effects (font (size 1.27 1.27)) hide)
    )
    (property "Datasheet" "" (at 41.91 309.88 0)
      (effects (font (size 1.27 1.27)) hide)
    )
    (pin "1")
    (instances
      (project "sdi-mipi-bridge"
        (path ""
          (reference "#PWR0135") (unit 1)
        )
      )
    )
  )

  (symbol (lib_id "sdi-mipi-bridge:GNDA") (at 176.53 271.78 0) (unit 1)
    (in_bom yes) (on_board yes) (dnp no)
    (property "Reference" "#PWR0102" (at 176.53 278.13 0)
      (effects (font (size 1.27 1.27)) hide)
    )
    (property "Value" "GNDA" (at 176.53 275.59 0)
      (effects (font (size 1.27 1.27)))
    )
    (property "Footprint" "" (at 176.53 271.78 0)
      (effects (font (size 1.27 1.27)) hide)
    )
    (property "Datasheet" "" (at 176.53 271.78 0)
      (effects (font (size 1.27 1.27)) hide)
    )
    (pin "1")
    (instances
      (project "sdi-mipi-bridge"
        (path ""
          (reference "#PWR0102") (unit 1)
        )
      )
    )
  )

  (symbol (lib_id "sdi-mipi-bridge:GNDREF") (at 260.35 306.07 0) (unit 1)
    (in_bom yes) (on_board yes) (dnp no)
    (property "Reference" "#PWR0143" (at 260.35 312.42 0)
      (effects (font (size 1.27 1.27)) hide)
    )
    (property "Value" "GNDREF" (at 260.477 310.4642 0)
      (effects (font (size 1.27 1.27)))
    )
    (property "Footprint" "" (at 260.35 306.07 0)
      (effects (font (size 1.27 1.27)) hide)
    )
    (property "Datasheet" "" (at 260.35 306.07 0)
      (effects (font (size 1.27 1.27)) hide)
    )
    (pin "1")
    (instances
      (project "sdi-mipi-bridge"
        (path ""
          (reference "#PWR0143") (unit 1)
        )
      )
    )
  )

  (symbol (lib_id "sdi-mipi-bridge:GNDREF") (at 246.38 233.68 0) (unit 1)
    (in_bom yes) (on_board yes) (dnp no)
    (property "Reference" "#PWR0129" (at 246.38 240.03 0)
      (effects (font (size 1.27 1.27)) hide)
    )
    (property "Value" "GNDREF" (at 246.507 238.0742 0)
      (effects (font (size 1.27 1.27)))
    )
    (property "Footprint" "" (at 246.38 233.68 0)
      (effects (font (size 1.27 1.27)) hide)
    )
    (property "Datasheet" "" (at 246.38 233.68 0)
      (effects (font (size 1.27 1.27)) hide)
    )
    (pin "1")
    (instances
      (project "sdi-mipi-bridge"
        (path ""
          (reference "#PWR0129") (unit 1)
        )
      )
    )
  )

  (symbol (lib_id "sdi-mipi-bridge:GNDREF") (at 57.15 337.82 0) (unit 1)
    (in_bom yes) (on_board yes) (dnp no)
    (property "Reference" "#PWR0141" (at 57.15 344.17 0)
      (effects (font (size 1.27 1.27)) hide)
    )
    (property "Value" "GNDREF" (at 57.277 342.2142 0)
      (effects (font (size 1.27 1.27)))
    )
    (property "Footprint" "" (at 57.15 337.82 0)
      (effects (font (size 1.27 1.27)) hide)
    )
    (property "Datasheet" "" (at 57.15 337.82 0)
      (effects (font (size 1.27 1.27)) hide)
    )
    (pin "1")
    (instances
      (project "sdi-mipi-bridge"
        (path ""
          (reference "#PWR0141") (unit 1)
        )
      )
    )
  )

  (symbol (lib_id "sdi-mipi-bridge:R_10k_0402") (at 326.39 322.58 90) (unit 1)
    (in_bom yes) (on_board yes) (dnp no)
    (property "Reference" "R66" (at 326.39 327.66 0)
      (effects (font (size 1.27 1.27)) (justify right))
    )
    (property "Value" "R_10k_0402" (at 330.2 322.58 0)
      (effects (font (size 1.524 1.524)) hide)
    )
    (property "Footprint" "sdi-mipi-bridge-footprints:R_0402_1005Metric" (at 321.31 317.5 0)
      (effects (font (size 1.524 1.524)) (justify left) hide)
    )
    (property "Datasheet" "https://www.bourns.com/docs/product-datasheets/cr.pdf" (at 326.39 322.58 0)
      (effects (font (size 1.27 1.27)) hide)
    )
    (property "Manufacturer" "Bourns" (at 316.23 317.5 0)
      (effects (font (size 1.524 1.524)) (justify left) hide)
    )
    (property "MPN" "CR0402-FX-1002GLF" (at 318.77 317.5 0)
      (effects (font (size 1.524 1.524)) (justify left) hide)
    )
    (property "Val" "10k" (at 325.12 322.58 0)
      (effects (font (size 1.27 1.27)) (justify right))
    )
    (property "DNP" "DNP" (at 326.39 320.04 0)
      (effects (font (size 1.27 1.27)))
    )
    (property "License" "Apache-2.0" (at 351.79 302.26 0)
      (effects (font (size 1.27 1.27) (thickness 0.15)) (justify left bottom) hide)
    )
    (property "Author" "Antmicro" (at 354.33 302.26 0)
      (effects (font (size 1.27 1.27) (thickness 0.15)) (justify left bottom) hide)
    )
    (property "Tolerance" "1%" (at 336.55 302.26 0)
      (effects (font (size 1.27 1.27)) (justify left bottom) hide)
    )
    (pin "1")
    (pin "2")
    (instances
      (project "sdi-mipi-bridge"
        (path ""
          (reference "R66") (unit 1)
        )
      )
    )
  )

  (symbol (lib_id "sdi-mipi-bridge:GNDREF") (at 508 68.58 0) (unit 1)
    (in_bom yes) (on_board yes) (dnp no)
    (property "Reference" "#PWR0149" (at 508 74.93 0)
      (effects (font (size 1.27 1.27)) hide)
    )
    (property "Value" "GNDREF" (at 508.127 72.9742 0)
      (effects (font (size 1.27 1.27)))
    )
    (property "Footprint" "" (at 508 68.58 0)
      (effects (font (size 1.27 1.27)) hide)
    )
    (property "Datasheet" "" (at 508 68.58 0)
      (effects (font (size 1.27 1.27)) hide)
    )
    (pin "1")
    (instances
      (project "sdi-mipi-bridge"
        (path ""
          (reference "#PWR0149") (unit 1)
        )
      )
    )
  )

  (symbol (lib_id "sdi-mipi-bridge:GS2971A") (at 179.07 48.26 0) (unit 2)
    (in_bom yes) (on_board yes) (dnp no) (fields_autoplaced)
    (property "Reference" "U2" (at 194.945 41.275 0)
      (effects (font (size 1.27 1.27) (thickness 0.15)))
    )
    (property "Value" "GS2971A" (at 194.945 43.815 0)
      (effects (font (size 1.27 1.27) (thickness 0.15)))
    )
    (property "Footprint" "sdi-mipi-bridge-footprints:BGA100_11x11mm_SEMTECH" (at 234.95 55.88 0)
      (effects (font (size 1.27 1.27) (thickness 0.15)) (justify left bottom) hide)
    )
    (property "Datasheet" "https://semtech.my.salesforce.com/sfc/p/#E0000000JelG/a/44000000MD3i/kpmMkrmUWgHlbCOwdLzVohMm1SDPoVH85guEGK.KXTc" (at 234.95 58.42 0)
      (effects (font (size 1.27 1.27) (thickness 0.15)) (justify left bottom) hide)
    )
    (property "MPN" "GS2971A" (at 234.95 60.96 0)
      (effects (font (size 1.27 1.27) (thickness 0.15)) (justify left bottom) hide)
    )
    (property "Manufacturer" "Semtech" (at 234.95 63.5 0)
      (effects (font (size 1.27 1.27) (thickness 0.15)) (justify left bottom) hide)
    )
    (property "Author" "Antmicro" (at 234.95 66.04 0)
      (effects (font (size 1.27 1.27) (thickness 0.15)) (justify left bottom) hide)
    )
    (property "License" "Apache-2.0" (at 234.95 68.58 0)
      (effects (font (size 1.27 1.27) (thickness 0.15)) (justify left bottom) hide)
    )
    (pin "A10")
    (pin "A5")
    (pin "A6")
    (pin "A8")
    (pin "A9")
    (pin "B10")
    (pin "B5")
    (pin "B6")
    (pin "B8")
    (pin "B9")
    (pin "C10")
    (pin "C5")
    (pin "C6")
    (pin "C8")
    (pin "C9")
    (pin "E10")
    (pin "E9")
    (pin "F10")
    (pin "F9")
    (pin "H10")
    (pin "H4")
    (pin "H9")
    (pin "J1")
    (pin "J10")
    (pin "J3")
    (pin "J4")
    (pin "J5")
    (pin "J8")
    (pin "J9")
    (pin "K1")
    (pin "K10")
    (pin "K3")
    (pin "K4")
    (pin "K5")
    (pin "K8")
    (pin "K9")
    (pin "A1")
    (pin "A2")
    (pin "A3")
    (pin "B3")
    (pin "C1")
    (pin "C7")
    (pin "D1")
    (pin "D7")
    (pin "D8")
    (pin "E7")
    (pin "E8")
    (pin "F1")
    (pin "F2")
    (pin "F7")
    (pin "F8")
    (pin "G1")
    (pin "G3")
    (pin "G7")
    (pin "G8")
    (pin "H3")
    (pin "H5")
    (pin "H6")
    (pin "H7")
    (pin "H8")
    (pin "J2")
    (pin "J6")
    (pin "K2")
    (pin "K6")
    (pin "A4")
    (pin "A7")
    (pin "B1")
    (pin "B2")
    (pin "B4")
    (pin "B7")
    (pin "C2")
    (pin "C3")
    (pin "C4")
    (pin "D10")
    (pin "D2")
    (pin "D3")
    (pin "D4")
    (pin "D5")
    (pin "D6")
    (pin "D9")
    (pin "E1")
    (pin "E2")
    (pin "E3")
    (pin "E4")
    (pin "E5")
    (pin "E6")
    (pin "F3")
    (pin "F4")
    (pin "F5")
    (pin "F6")
    (pin "G10")
    (pin "G2")
    (pin "G4")
    (pin "G5")
    (pin "G6")
    (pin "G9")
    (pin "H1")
    (pin "H2")
    (pin "J7")
    (pin "K7")
    (instances
      (project "sdi-mipi-bridge"
        (path ""
          (reference "U2") (unit 2)
        )
      )
    )
  )

  (symbol (lib_id "sdi-mipi-bridge:R_10k_0402") (at 382.27 322.58 90) (unit 1)
    (in_bom yes) (on_board yes) (dnp no)
    (property "Reference" "R104" (at 382.27 327.66 0)
      (effects (font (size 1.27 1.27)) (justify right))
    )
    (property "Value" "R_10k_0402" (at 386.08 322.58 0)
      (effects (font (size 1.524 1.524)) hide)
    )
    (property "Footprint" "sdi-mipi-bridge-footprints:R_0402_1005Metric" (at 377.19 317.5 0)
      (effects (font (size 1.524 1.524)) (justify left) hide)
    )
    (property "Datasheet" "https://www.bourns.com/docs/product-datasheets/cr.pdf" (at 382.27 322.58 0)
      (effects (font (size 1.27 1.27)) hide)
    )
    (property "Manufacturer" "Bourns" (at 372.11 317.5 0)
      (effects (font (size 1.524 1.524)) (justify left) hide)
    )
    (property "MPN" "CR0402-FX-1002GLF" (at 374.65 317.5 0)
      (effects (font (size 1.524 1.524)) (justify left) hide)
    )
    (property "Val" "10k" (at 381 322.58 0)
      (effects (font (size 1.27 1.27)) (justify right))
    )
    (property "DNP" "" (at 382.27 320.04 0)
      (effects (font (size 1.27 1.27)))
    )
    (property "License" "Apache-2.0" (at 407.67 302.26 0)
      (effects (font (size 1.27 1.27) (thickness 0.15)) (justify left bottom) hide)
    )
    (property "Author" "Antmicro" (at 410.21 302.26 0)
      (effects (font (size 1.27 1.27) (thickness 0.15)) (justify left bottom) hide)
    )
    (property "Tolerance" "1%" (at 392.43 302.26 0)
      (effects (font (size 1.27 1.27)) (justify left bottom) hide)
    )
    (pin "1")
    (pin "2")
    (instances
      (project "sdi-mipi-bridge"
        (path ""
          (reference "R104") (unit 1)
        )
      )
    )
  )

  (symbol (lib_id "sdi-mipi-bridge:VPP") (at 325.12 140.97 0) (unit 1)
    (in_bom yes) (on_board yes) (dnp no)
    (property "Reference" "#PWR0157" (at 325.12 144.78 0)
      (effects (font (size 1.27 1.27)) hide)
    )
    (property "Value" "VPP" (at 325.12 137.16 0)
      (effects (font (size 1.27 1.27)))
    )
    (property "Footprint" "" (at 325.12 140.97 0)
      (effects (font (size 1.27 1.27)) hide)
    )
    (property "Datasheet" "" (at 325.12 140.97 0)
      (effects (font (size 1.27 1.27)) hide)
    )
    (pin "1")
    (instances
      (project "sdi-mipi-bridge"
        (path ""
          (reference "#PWR0157") (unit 1)
        )
      )
    )
  )

  (symbol (lib_id "sdi-mipi-bridge:GNDA") (at 320.04 328.93 0) (unit 1)
    (in_bom yes) (on_board yes) (dnp no)
    (property "Reference" "#PWR01" (at 320.04 335.28 0)
      (effects (font (size 1.27 1.27)) hide)
    )
    (property "Value" "GNDA" (at 320.167 333.3242 0)
      (effects (font (size 1.27 1.27)))
    )
    (property "Footprint" "" (at 320.04 328.93 0)
      (effects (font (size 1.27 1.27)) hide)
    )
    (property "Datasheet" "" (at 320.04 328.93 0)
      (effects (font (size 1.27 1.27)) hide)
    )
    (pin "1")
    (instances
      (project "sdi-mipi-bridge"
        (path ""
          (reference "#PWR01") (unit 1)
        )
      )
    )
  )

  (symbol (lib_id "sdi-mipi-bridge:PWR_FLAG") (at 271.78 224.79 0) (unit 1)
    (in_bom yes) (on_board yes) (dnp no)
    (property "Reference" "#FLG0105" (at 271.78 222.885 0)
      (effects (font (size 1.27 1.27)) hide)
    )
    (property "Value" "PWR_FLAG" (at 271.78 220.98 0)
      (effects (font (size 1.27 1.27)))
    )
    (property "Footprint" "" (at 271.78 224.79 0)
      (effects (font (size 1.27 1.27)) hide)
    )
    (property "Datasheet" "" (at 271.78 224.79 0)
      (effects (font (size 1.27 1.27)) hide)
    )
    (pin "1")
    (instances
      (project "sdi-mipi-bridge"
        (path ""
          (reference "#FLG0105") (unit 1)
        )
      )
    )
  )

  (symbol (lib_id "sdi-mipi-bridge:GNDA") (at 360.68 388.62 0) (unit 1)
    (in_bom yes) (on_board yes) (dnp no)
    (property "Reference" "#PWR07" (at 360.68 394.97 0)
      (effects (font (size 1.27 1.27)) hide)
    )
    (property "Value" "GNDA" (at 360.807 393.0142 0)
      (effects (font (size 1.27 1.27)))
    )
    (property "Footprint" "" (at 360.68 388.62 0)
      (effects (font (size 1.27 1.27)) hide)
    )
    (property "Datasheet" "" (at 360.68 388.62 0)
      (effects (font (size 1.27 1.27)) hide)
    )
    (pin "1")
    (instances
      (project "sdi-mipi-bridge"
        (path ""
          (reference "#PWR07") (unit 1)
        )
      )
    )
  )

  (symbol (lib_id "sdi-mipi-bridge:VDD") (at 146.05 165.1 0) (unit 1)
    (in_bom yes) (on_board yes) (dnp no)
    (property "Reference" "#PWR0152" (at 146.05 168.91 0)
      (effects (font (size 1.27 1.27)) hide)
    )
    (property "Value" "VDD" (at 146.05 161.29 0)
      (effects (font (size 1.27 1.27)))
    )
    (property "Footprint" "" (at 146.05 165.1 0)
      (effects (font (size 1.27 1.27)) hide)
    )
    (property "Datasheet" "" (at 146.05 165.1 0)
      (effects (font (size 1.27 1.27)) hide)
    )
    (pin "1")
    (instances
      (project "sdi-mipi-bridge"
        (path ""
          (reference "#PWR0152") (unit 1)
        )
      )
    )
  )

  (symbol (lib_id "sdi-mipi-bridge:GNDREF") (at 312.42 74.93 0) (unit 1)
    (in_bom yes) (on_board yes) (dnp no)
    (property "Reference" "#PWR0145" (at 312.42 81.28 0)
      (effects (font (size 1.27 1.27)) hide)
    )
    (property "Value" "GNDREF" (at 312.547 79.3242 0)
      (effects (font (size 1.27 1.27)))
    )
    (property "Footprint" "" (at 312.42 74.93 0)
      (effects (font (size 1.27 1.27)) hide)
    )
    (property "Datasheet" "" (at 312.42 74.93 0)
      (effects (font (size 1.27 1.27)) hide)
    )
    (pin "1")
    (instances
      (project "sdi-mipi-bridge"
        (path ""
          (reference "#PWR0145") (unit 1)
        )
      )
    )
  )

  (symbol (lib_id "sdi-mipi-bridge:VDD") (at 95.25 157.48 0) (unit 1)
    (in_bom yes) (on_board yes) (dnp no)
    (property "Reference" "#PWR0151" (at 95.25 161.29 0)
      (effects (font (size 1.27 1.27)) hide)
    )
    (property "Value" "VDD" (at 95.25 153.67 0)
      (effects (font (size 1.27 1.27)))
    )
    (property "Footprint" "" (at 95.25 157.48 0)
      (effects (font (size 1.27 1.27)) hide)
    )
    (property "Datasheet" "" (at 95.25 157.48 0)
      (effects (font (size 1.27 1.27)) hide)
    )
    (pin "1")
    (instances
      (project "sdi-mipi-bridge"
        (path ""
          (reference "#PWR0151") (unit 1)
        )
      )
    )
  )

  (symbol (lib_id "sdi-mipi-bridge:GNDREF") (at 49.53 309.88 0) (unit 1)
    (in_bom yes) (on_board yes) (dnp no)
    (property "Reference" "#PWR0133" (at 49.53 316.23 0)
      (effects (font (size 1.27 1.27)) hide)
    )
    (property "Value" "GNDREF" (at 49.657 314.2742 0)
      (effects (font (size 1.27 1.27)))
    )
    (property "Footprint" "" (at 49.53 309.88 0)
      (effects (font (size 1.27 1.27)) hide)
    )
    (property "Datasheet" "" (at 49.53 309.88 0)
      (effects (font (size 1.27 1.27)) hide)
    )
    (pin "1")
    (instances
      (project "sdi-mipi-bridge"
        (path ""
          (reference "#PWR0133") (unit 1)
        )
      )
    )
  )

  (symbol (lib_id "sdi-mipi-bridge:R_10k_0402") (at 382.27 299.72 90) (unit 1)
    (in_bom yes) (on_board yes) (dnp no)
    (property "Reference" "R103" (at 382.27 287.02 0)
      (effects (font (size 1.27 1.27)) (justify right))
    )
    (property "Value" "R_10k_0402" (at 386.08 299.72 0)
      (effects (font (size 1.524 1.524)) hide)
    )
    (property "Footprint" "sdi-mipi-bridge-footprints:R_0402_1005Metric" (at 377.19 294.64 0)
      (effects (font (size 1.524 1.524)) (justify left) hide)
    )
    (property "Datasheet" "https://www.bourns.com/docs/product-datasheets/cr.pdf" (at 382.27 299.72 0)
      (effects (font (size 1.27 1.27)) hide)
    )
    (property "Manufacturer" "Bourns" (at 372.11 294.64 0)
      (effects (font (size 1.524 1.524)) (justify left) hide)
    )
    (property "MPN" "CR0402-FX-1002GLF" (at 374.65 294.64 0)
      (effects (font (size 1.524 1.524)) (justify left) hide)
    )
    (property "Val" "10k" (at 381 299.72 0)
      (effects (font (size 1.27 1.27)) (justify right))
    )
    (property "License" "Apache-2.0" (at 407.67 279.4 0)
      (effects (font (size 1.27 1.27) (thickness 0.15)) (justify left bottom) hide)
    )
    (property "Author" "Antmicro" (at 410.21 279.4 0)
      (effects (font (size 1.27 1.27) (thickness 0.15)) (justify left bottom) hide)
    )
    (property "Tolerance" "1%" (at 392.43 279.4 0)
      (effects (font (size 1.27 1.27)) (justify left bottom) hide)
    )
    (property "DNP" "DNP" (at 382.27 297.18 0)
      (effects (font (size 1.27 1.27)))
    )
    (pin "1")
    (pin "2")
    (instances
      (project "sdi-mipi-bridge"
        (path ""
          (reference "R103") (unit 1)
        )
      )
    )
  )

  (symbol (lib_id "sdi-mipi-bridge:PinHeader_1x4_P1.27mm_Drill0.7mm") (at 35.56 154.94 0) (mirror y) (unit 1)
    (in_bom yes) (on_board yes) (dnp no) (fields_autoplaced)
    (property "Reference" "J5" (at 31.75 148.59 0)
      (effects (font (size 1.27 1.27) (thickness 0.15)))
    )
    (property "Value" "PinHeader_1x4_P1.27mm_Drill.7mm" (at 15.24 165.1 0)
      (effects (font (size 1.27 1.27) (thickness 0.15)) (justify left bottom) hide)
    )
    (property "Footprint" "sdi-mipi-bridge-footprints:PinHeader_1x4_P1.27mm_Drill0.7mm" (at 15.24 167.64 0)
      (effects (font (size 1.27 1.27) (thickness 0.15)) (justify left bottom) hide)
    )
    (property "Datasheet" "http://www.farnell.com/datasheets/2605295.pdf" (at 15.24 170.18 0)
      (effects (font (size 1.27 1.27) (thickness 0.15)) (justify left bottom) hide)
    )
    (property "MPN" "MC-HVT1-S04-G" (at 31.75 151.13 0)
      (effects (font (size 1.27 1.27) (thickness 0.15)))
    )
    (property "Manufacturer" "Multicomp Pro" (at 15.24 172.72 0)
      (effects (font (size 1.27 1.27) (thickness 0.15)) (justify left bottom) hide)
    )
    (property "Author" "Antmicro" (at 15.24 175.26 0)
      (effects (font (size 1.27 1.27) (thickness 0.15)) (justify left bottom) hide)
    )
    (property "License" "Apache-2.0" (at 15.24 177.8 0)
      (effects (font (size 1.27 1.27) (thickness 0.15)) (justify left bottom) hide)
    )
    (pin "1")
    (pin "2")
    (pin "3")
    (pin "4")
    (instances
      (project "sdi-mipi-bridge"
        (path ""
          (reference "J5") (unit 1)
        )
      )
    )
  )

  (symbol (lib_id "sdi-mipi-bridge:PWR_FLAG") (at 434.34 162.56 180) (unit 1)
    (in_bom yes) (on_board yes) (dnp no)
    (property "Reference" "#FLG0113" (at 434.34 164.465 0)
      (effects (font (size 1.27 1.27)) hide)
    )
    (property "Value" "PWR_FLAG" (at 434.34 166.37 0)
      (effects (font (size 1.27 1.27)))
    )
    (property "Footprint" "" (at 434.34 162.56 0)
      (effects (font (size 1.27 1.27)) hide)
    )
    (property "Datasheet" "" (at 434.34 162.56 0)
      (effects (font (size 1.27 1.27)) hide)
    )
    (pin "1")
    (instances
      (project "sdi-mipi-bridge"
        (path ""
          (reference "#FLG0113") (unit 1)
        )
      )
    )
  )

  (symbol (lib_id "sdi-mipi-bridge:R_10k_0402") (at 386.08 322.58 90) (unit 1)
    (in_bom yes) (on_board yes) (dnp no)
    (property "Reference" "R107" (at 386.08 327.66 0)
      (effects (font (size 1.27 1.27)) (justify right))
    )
    (property "Value" "R_10k_0402" (at 389.89 322.58 0)
      (effects (font (size 1.524 1.524)) hide)
    )
    (property "Footprint" "sdi-mipi-bridge-footprints:R_0402_1005Metric" (at 381 317.5 0)
      (effects (font (size 1.524 1.524)) (justify left) hide)
    )
    (property "Datasheet" "https://www.bourns.com/docs/product-datasheets/cr.pdf" (at 386.08 322.58 0)
      (effects (font (size 1.27 1.27)) hide)
    )
    (property "Manufacturer" "Bourns" (at 375.92 317.5 0)
      (effects (font (size 1.524 1.524)) (justify left) hide)
    )
    (property "MPN" "CR0402-FX-1002GLF" (at 378.46 317.5 0)
      (effects (font (size 1.524 1.524)) (justify left) hide)
    )
    (property "Val" "10k" (at 384.81 322.58 0)
      (effects (font (size 1.27 1.27)) (justify right))
    )
    (property "License" "Apache-2.0" (at 411.48 302.26 0)
      (effects (font (size 1.27 1.27) (thickness 0.15)) (justify left bottom) hide)
    )
    (property "Author" "Antmicro" (at 414.02 302.26 0)
      (effects (font (size 1.27 1.27) (thickness 0.15)) (justify left bottom) hide)
    )
    (property "Tolerance" "1%" (at 396.24 302.26 0)
      (effects (font (size 1.27 1.27)) (justify left bottom) hide)
    )
    (pin "1")
    (pin "2")
    (instances
      (project "sdi-mipi-bridge"
        (path ""
          (reference "R107") (unit 1)
        )
      )
    )
  )

  (symbol (lib_id "sdi-mipi-bridge:PWR_FLAG") (at 186.69 262.89 0) (unit 1)
    (in_bom yes) (on_board yes) (dnp no)
    (property "Reference" "#FLG0101" (at 186.69 260.985 0)
      (effects (font (size 1.27 1.27)) hide)
    )
    (property "Value" "PWR_FLAG" (at 186.69 259.08 0)
      (effects (font (size 1.27 1.27)))
    )
    (property "Footprint" "" (at 186.69 262.89 0)
      (effects (font (size 1.27 1.27)) hide)
    )
    (property "Datasheet" "" (at 186.69 262.89 0)
      (effects (font (size 1.27 1.27)) hide)
    )
    (pin "1")
    (instances
      (project "sdi-mipi-bridge"
        (path ""
          (reference "#FLG0101") (unit 1)
        )
      )
    )
  )

  (symbol (lib_id "sdi-mipi-bridge:R_10k_0402") (at 337.82 322.58 90) (unit 1)
    (in_bom yes) (on_board yes) (dnp no)
    (property "Reference" "R79" (at 337.82 327.66 0)
      (effects (font (size 1.27 1.27)) (justify right))
    )
    (property "Value" "R_10k_0402" (at 341.63 322.58 0)
      (effects (font (size 1.524 1.524)) hide)
    )
    (property "Footprint" "sdi-mipi-bridge-footprints:R_0402_1005Metric" (at 332.74 317.5 0)
      (effects (font (size 1.524 1.524)) (justify left) hide)
    )
    (property "Datasheet" "https://www.bourns.com/docs/product-datasheets/cr.pdf" (at 337.82 322.58 0)
      (effects (font (size 1.27 1.27)) hide)
    )
    (property "Manufacturer" "Bourns" (at 327.66 317.5 0)
      (effects (font (size 1.524 1.524)) (justify left) hide)
    )
    (property "MPN" "CR0402-FX-1002GLF" (at 330.2 317.5 0)
      (effects (font (size 1.524 1.524)) (justify left) hide)
    )
    (property "Val" "10k" (at 336.55 322.58 0)
      (effects (font (size 1.27 1.27)) (justify right))
    )
    (property "DNP" "DNP" (at 337.82 320.04 0)
      (effects (font (size 1.27 1.27)))
    )
    (property "License" "Apache-2.0" (at 363.22 302.26 0)
      (effects (font (size 1.27 1.27) (thickness 0.15)) (justify left bottom) hide)
    )
    (property "Author" "Antmicro" (at 365.76 302.26 0)
      (effects (font (size 1.27 1.27) (thickness 0.15)) (justify left bottom) hide)
    )
    (property "Tolerance" "1%" (at 347.98 302.26 0)
      (effects (font (size 1.27 1.27)) (justify left bottom) hide)
    )
    (pin "1")
    (pin "2")
    (instances
      (project "sdi-mipi-bridge"
        (path ""
          (reference "R79") (unit 1)
        )
      )
    )
  )

  (symbol (lib_id "sdi-mipi-bridge:PinHeader_2x5_P1.27mm_Drill0.65mm") (at 34.29 119.38 0) (unit 1)
    (in_bom yes) (on_board yes) (dnp no) (fields_autoplaced)
    (property "Reference" "J6" (at 39.37 113.03 0)
      (effects (font (size 1.27 1.27) (thickness 0.15)))
    )
    (property "Value" "PinHeader_2x5_P1.27mm_Vertical" (at 59.69 129.54 0)
      (effects (font (size 1.27 1.27) (thickness 0.15)) (justify left bottom) hide)
    )
    (property "Footprint" "sdi-mipi-bridge-footprints:PinHeader_2x5_P1.27mm_Drill0.65mm" (at 59.69 132.08 0)
      (effects (font (size 1.27 1.27) (thickness 0.15)) (justify left bottom) hide)
    )
    (property "Datasheet" "https://www.farnell.com/datasheets/3108040.pdf" (at 59.69 134.62 0)
      (effects (font (size 1.27 1.27) (thickness 0.15)) (justify left bottom) hide)
    )
    (property "MPN" "2199SB-10G-301523" (at 39.37 115.57 0)
      (effects (font (size 1.27 1.27) (thickness 0.15)))
    )
    (property "Manufacturer" "Multicomp Pro" (at 59.69 137.16 0)
      (effects (font (size 1.27 1.27) (thickness 0.15)) (justify left bottom) hide)
    )
    (property "Author" "Antmicro" (at 59.69 139.7 0)
      (effects (font (size 1.27 1.27) (thickness 0.15)) (justify left bottom) hide)
    )
    (property "License" "Apache-2.0" (at 59.69 142.24 0)
      (effects (font (size 1.27 1.27) (thickness 0.15)) (justify left bottom) hide)
    )
    (pin "1")
    (pin "10")
    (pin "2")
    (pin "3")
    (pin "4")
    (pin "5")
    (pin "6")
    (pin "7")
    (pin "8")
    (pin "9")
    (instances
      (project "sdi-mipi-bridge"
        (path ""
          (reference "J6") (unit 1)
        )
      )
    )
  )

  (symbol (lib_id "sdi-mipi-bridge:GNDREF") (at 265.43 233.68 0) (unit 1)
    (in_bom yes) (on_board yes) (dnp no)
    (property "Reference" "#PWR0146" (at 265.43 240.03 0)
      (effects (font (size 1.27 1.27)) hide)
    )
    (property "Value" "GNDREF" (at 265.557 238.0742 0)
      (effects (font (size 1.27 1.27)))
    )
    (property "Footprint" "" (at 265.43 233.68 0)
      (effects (font (size 1.27 1.27)) hide)
    )
    (property "Datasheet" "" (at 265.43 233.68 0)
      (effects (font (size 1.27 1.27)) hide)
    )
    (pin "1")
    (instances
      (project "sdi-mipi-bridge"
        (path ""
          (reference "#PWR0146") (unit 1)
        )
      )
    )
  )

  (symbol (lib_id "sdi-mipi-bridge:R_10k_0402") (at 330.2 322.58 90) (unit 1)
    (in_bom yes) (on_board yes) (dnp no)
    (property "Reference" "R75" (at 330.2 327.66 0)
      (effects (font (size 1.27 1.27)) (justify right))
    )
    (property "Value" "R_10k_0402" (at 334.01 322.58 0)
      (effects (font (size 1.524 1.524)) hide)
    )
    (property "Footprint" "sdi-mipi-bridge-footprints:R_0402_1005Metric" (at 325.12 317.5 0)
      (effects (font (size 1.524 1.524)) (justify left) hide)
    )
    (property "Datasheet" "https://www.bourns.com/docs/product-datasheets/cr.pdf" (at 330.2 322.58 0)
      (effects (font (size 1.27 1.27)) hide)
    )
    (property "Manufacturer" "Bourns" (at 320.04 317.5 0)
      (effects (font (size 1.524 1.524)) (justify left) hide)
    )
    (property "MPN" "CR0402-FX-1002GLF" (at 322.58 317.5 0)
      (effects (font (size 1.524 1.524)) (justify left) hide)
    )
    (property "Val" "10k" (at 328.93 322.58 0)
      (effects (font (size 1.27 1.27)) (justify right))
    )
    (property "DNP" "DNP" (at 330.2 320.04 0)
      (effects (font (size 1.27 1.27)))
    )
    (property "License" "Apache-2.0" (at 355.6 302.26 0)
      (effects (font (size 1.27 1.27) (thickness 0.15)) (justify left bottom) hide)
    )
    (property "Author" "Antmicro" (at 358.14 302.26 0)
      (effects (font (size 1.27 1.27) (thickness 0.15)) (justify left bottom) hide)
    )
    (property "Tolerance" "1%" (at 340.36 302.26 0)
      (effects (font (size 1.27 1.27)) (justify left bottom) hide)
    )
    (pin "1")
    (pin "2")
    (instances
      (project "sdi-mipi-bridge"
        (path ""
          (reference "R75") (unit 1)
        )
      )
    )
  )

  (symbol (lib_id "sdi-mipi-bridge:PWR_FLAG") (at 187.96 236.22 0) (mirror x) (unit 1)
    (in_bom yes) (on_board yes) (dnp no)
    (property "Reference" "#FLG0102" (at 187.96 238.125 0)
      (effects (font (size 1.27 1.27)) hide)
    )
    (property "Value" "PWR_FLAG" (at 187.96 240.03 0)
      (effects (font (size 1.27 1.27)))
    )
    (property "Footprint" "" (at 187.96 236.22 0)
      (effects (font (size 1.27 1.27)) hide)
    )
    (property "Datasheet" "" (at 187.96 236.22 0)
      (effects (font (size 1.27 1.27)) hide)
    )
    (pin "1")
    (instances
      (project "sdi-mipi-bridge"
        (path ""
          (reference "#FLG0102") (unit 1)
        )
      )
    )
  )

  (symbol (lib_id "sdi-mipi-bridge:R_10k_0402") (at 373.38 161.29 90) (unit 1)
    (in_bom yes) (on_board yes) (dnp no)
    (property "Reference" "R84" (at 375.285 157.48 90)
      (effects (font (size 1.27 1.27)) (justify right))
    )
    (property "Value" "R_10k_0402" (at 386.08 140.97 0)
      (effects (font (size 1.27 1.27) (thickness 0.15)) (justify left bottom) hide)
    )
    (property "Footprint" "sdi-mipi-bridge-footprints:R_0402_1005Metric" (at 388.62 140.97 0)
      (effects (font (size 1.27 1.27) (thickness 0.15)) (justify left bottom) hide)
    )
    (property "Datasheet" "https://www.bourns.com/docs/product-datasheets/cr.pdf" (at 391.16 140.97 0)
      (effects (font (size 1.27 1.27) (thickness 0.15)) (justify left bottom) hide)
    )
    (property "Manufacturer" "Bourns" (at 396.24 140.97 0)
      (effects (font (size 1.27 1.27) (thickness 0.15)) (justify left bottom) hide)
    )
    (property "MPN" "CR0402-FX-1002GLF" (at 393.7 140.97 0)
      (effects (font (size 1.27 1.27) (thickness 0.15)) (justify left bottom) hide)
    )
    (property "Val" "10k" (at 375.285 160.0201 90)
      (effects (font (size 1.27 1.27) (thickness 0.15)) (justify right))
    )
    (property "DNP" "DNP" (at 373.38 156.845 0)
      (effects (font (size 1.27 1.27)) (justify right))
    )
    (property "License" "Apache-2.0" (at 398.78 140.97 0)
      (effects (font (size 1.27 1.27) (thickness 0.15)) (justify left bottom) hide)
    )
    (property "Author" "Antmicro" (at 401.32 140.97 0)
      (effects (font (size 1.27 1.27) (thickness 0.15)) (justify left bottom) hide)
    )
    (property "Tolerance" "1%" (at 383.54 140.97 0)
      (effects (font (size 1.27 1.27)) (justify left bottom) hide)
    )
    (pin "1")
    (pin "2")
    (instances
      (project "sdi-mipi-bridge"
        (path ""
          (reference "R84") (unit 1)
        )
      )
    )
  )

  (symbol (lib_id "sdi-mipi-bridge:PWR_FLAG") (at 185.42 300.355 0) (unit 1)
    (in_bom yes) (on_board yes) (dnp no)
    (property "Reference" "#FLG0104" (at 185.42 298.45 0)
      (effects (font (size 1.27 1.27)) hide)
    )
    (property "Value" "PWR_FLAG" (at 185.42 296.545 0)
      (effects (font (size 1.27 1.27)))
    )
    (property "Footprint" "" (at 185.42 300.355 0)
      (effects (font (size 1.27 1.27)) hide)
    )
    (property "Datasheet" "" (at 185.42 300.355 0)
      (effects (font (size 1.27 1.27)) hide)
    )
    (pin "1")
    (instances
      (project "sdi-mipi-bridge"
        (path ""
          (reference "#FLG0104") (unit 1)
        )
      )
    )
  )

  (symbol (lib_id "sdi-mipi-bridge:R_10k_0402") (at 393.7 299.72 90) (unit 1)
    (in_bom yes) (on_board yes) (dnp no)
    (property "Reference" "R110" (at 393.7 287.02 0)
      (effects (font (size 1.27 1.27)) (justify right))
    )
    (property "Value" "R_10k_0402" (at 397.51 299.72 0)
      (effects (font (size 1.524 1.524)) hide)
    )
    (property "Footprint" "sdi-mipi-bridge-footprints:R_0402_1005Metric" (at 388.62 294.64 0)
      (effects (font (size 1.524 1.524)) (justify left) hide)
    )
    (property "Datasheet" "https://www.bourns.com/docs/product-datasheets/cr.pdf" (at 393.7 299.72 0)
      (effects (font (size 1.27 1.27)) hide)
    )
    (property "Manufacturer" "Bourns" (at 383.54 294.64 0)
      (effects (font (size 1.524 1.524)) (justify left) hide)
    )
    (property "MPN" "CR0402-FX-1002GLF" (at 386.08 294.64 0)
      (effects (font (size 1.524 1.524)) (justify left) hide)
    )
    (property "Val" "10k" (at 392.43 299.72 0)
      (effects (font (size 1.27 1.27)) (justify right))
    )
    (property "DNP" "DNP" (at 393.7 297.18 0)
      (effects (font (size 1.27 1.27)))
    )
    (property "License" "Apache-2.0" (at 419.1 279.4 0)
      (effects (font (size 1.27 1.27) (thickness 0.15)) (justify left bottom) hide)
    )
    (property "Author" "Antmicro" (at 421.64 279.4 0)
      (effects (font (size 1.27 1.27) (thickness 0.15)) (justify left bottom) hide)
    )
    (property "Tolerance" "1%" (at 403.86 279.4 0)
      (effects (font (size 1.27 1.27)) (justify left bottom) hide)
    )
    (pin "1")
    (pin "2")
    (instances
      (project "sdi-mipi-bridge"
        (path ""
          (reference "R110") (unit 1)
        )
      )
    )
  )

  (symbol (lib_id "sdi-mipi-bridge:GNDA") (at 167.64 311.15 0) (unit 1)
    (in_bom yes) (on_board yes) (dnp no)
    (property "Reference" "#PWR0109" (at 167.64 317.5 0)
      (effects (font (size 1.27 1.27)) hide)
    )
    (property "Value" "GNDA" (at 167.64 314.96 0)
      (effects (font (size 1.27 1.27)))
    )
    (property "Footprint" "" (at 167.64 311.15 0)
      (effects (font (size 1.27 1.27)) hide)
    )
    (property "Datasheet" "" (at 167.64 311.15 0)
      (effects (font (size 1.27 1.27)) hide)
    )
    (pin "1")
    (instances
      (project "sdi-mipi-bridge"
        (path ""
          (reference "#PWR0109") (unit 1)
        )
      )
    )
  )

  (symbol (lib_id "sdi-mipi-bridge:GNDA") (at 259.08 163.83 0) (unit 1)
    (in_bom yes) (on_board yes) (dnp no)
    (property "Reference" "#PWR0144" (at 259.08 170.18 0)
      (effects (font (size 1.27 1.27)) hide)
    )
    (property "Value" "GNDA" (at 259.08 167.64 0)
      (effects (font (size 1.27 1.27)))
    )
    (property "Footprint" "" (at 259.08 163.83 0)
      (effects (font (size 1.27 1.27)) hide)
    )
    (property "Datasheet" "" (at 259.08 163.83 0)
      (effects (font (size 1.27 1.27)) hide)
    )
    (pin "1")
    (instances
      (project "sdi-mipi-bridge"
        (path ""
          (reference "#PWR0144") (unit 1)
        )
      )
    )
  )

  (symbol (lib_id "sdi-mipi-bridge:VPP") (at 76.2 300.99 0) (unit 1)
    (in_bom yes) (on_board yes) (dnp no)
    (property "Reference" "#PWR0156" (at 76.2 304.8 0)
      (effects (font (size 1.27 1.27)) hide)
    )
    (property "Value" "VPP" (at 76.2 297.18 0)
      (effects (font (size 1.27 1.27)))
    )
    (property "Footprint" "" (at 76.2 300.99 0)
      (effects (font (size 1.27 1.27)) hide)
    )
    (property "Datasheet" "" (at 76.2 300.99 0)
      (effects (font (size 1.27 1.27)) hide)
    )
    (pin "1")
    (instances
      (project "sdi-mipi-bridge"
        (path ""
          (reference "#PWR0156") (unit 1)
        )
      )
    )
  )

  (symbol (lib_id "sdi-mipi-bridge:R_10k_0402") (at 345.44 322.58 90) (unit 1)
    (in_bom yes) (on_board yes) (dnp no)
    (property "Reference" "R97" (at 345.44 327.66 0)
      (effects (font (size 1.27 1.27)) (justify right))
    )
    (property "Value" "R_10k_0402" (at 349.25 322.58 0)
      (effects (font (size 1.524 1.524)) hide)
    )
    (property "Footprint" "sdi-mipi-bridge-footprints:R_0402_1005Metric" (at 340.36 317.5 0)
      (effects (font (size 1.524 1.524)) (justify left) hide)
    )
    (property "Datasheet" "https://www.bourns.com/docs/product-datasheets/cr.pdf" (at 345.44 322.58 0)
      (effects (font (size 1.27 1.27)) hide)
    )
    (property "Manufacturer" "Bourns" (at 335.28 317.5 0)
      (effects (font (size 1.524 1.524)) (justify left) hide)
    )
    (property "MPN" "CR0402-FX-1002GLF" (at 337.82 317.5 0)
      (effects (font (size 1.524 1.524)) (justify left) hide)
    )
    (property "Val" "10k" (at 344.17 322.58 0)
      (effects (font (size 1.27 1.27)) (justify right))
    )
    (property "License" "Apache-2.0" (at 370.84 302.26 0)
      (effects (font (size 1.27 1.27) (thickness 0.15)) (justify left bottom) hide)
    )
    (property "Author" "Antmicro" (at 373.38 302.26 0)
      (effects (font (size 1.27 1.27) (thickness 0.15)) (justify left bottom) hide)
    )
    (property "Tolerance" "1%" (at 355.6 302.26 0)
      (effects (font (size 1.27 1.27)) (justify left bottom) hide)
    )
    (property "DNP" "DNP" (at 345.44 320.04 0)
      (effects (font (size 1.27 1.27)))
    )
    (pin "1")
    (pin "2")
    (instances
      (project "sdi-mipi-bridge"
        (path ""
          (reference "R97") (unit 1)
        )
      )
    )
  )

  (symbol (lib_id "sdi-mipi-bridge:PWR_FLAG") (at 551.18 325.12 270) (unit 1)
    (in_bom yes) (on_board yes) (dnp no)
    (property "Reference" "#FLG0115" (at 553.085 325.12 0)
      (effects (font (size 1.27 1.27)) hide)
    )
    (property "Value" "PWR_FLAG" (at 558.8 325.12 90)
      (effects (font (size 1.27 1.27)))
    )
    (property "Footprint" "" (at 551.18 325.12 0)
      (effects (font (size 1.27 1.27)) hide)
    )
    (property "Datasheet" "" (at 551.18 325.12 0)
      (effects (font (size 1.27 1.27)) hide)
    )
    (pin "1")
    (instances
      (project "sdi-mipi-bridge"
        (path ""
          (reference "#FLG0115") (unit 1)
        )
      )
    )
  )

  (symbol (lib_id "sdi-mipi-bridge:R_10k_0402") (at 341.63 322.58 90) (unit 1)
    (in_bom yes) (on_board yes) (dnp no)
    (property "Reference" "R81" (at 341.63 327.66 0)
      (effects (font (size 1.27 1.27)) (justify right))
    )
    (property "Value" "R_10k_0402" (at 345.44 322.58 0)
      (effects (font (size 1.524 1.524)) hide)
    )
    (property "Footprint" "sdi-mipi-bridge-footprints:R_0402_1005Metric" (at 336.55 317.5 0)
      (effects (font (size 1.524 1.524)) (justify left) hide)
    )
    (property "Datasheet" "https://www.bourns.com/docs/product-datasheets/cr.pdf" (at 341.63 322.58 0)
      (effects (font (size 1.27 1.27)) hide)
    )
    (property "Manufacturer" "Bourns" (at 331.47 317.5 0)
      (effects (font (size 1.524 1.524)) (justify left) hide)
    )
    (property "MPN" "CR0402-FX-1002GLF" (at 334.01 317.5 0)
      (effects (font (size 1.524 1.524)) (justify left) hide)
    )
    (property "Val" "10k" (at 340.36 322.58 0)
      (effects (font (size 1.27 1.27)) (justify right))
    )
    (property "License" "Apache-2.0" (at 367.03 302.26 0)
      (effects (font (size 1.27 1.27) (thickness 0.15)) (justify left bottom) hide)
    )
    (property "Author" "Antmicro" (at 369.57 302.26 0)
      (effects (font (size 1.27 1.27) (thickness 0.15)) (justify left bottom) hide)
    )
    (property "Tolerance" "1%" (at 351.79 302.26 0)
      (effects (font (size 1.27 1.27)) (justify left bottom) hide)
    )
    (pin "1")
    (pin "2")
    (instances
      (project "sdi-mipi-bridge"
        (path ""
          (reference "R81") (unit 1)
        )
      )
    )
  )

  (symbol (lib_id "sdi-mipi-bridge:R_10k_0402") (at 374.65 322.58 90) (unit 1)
    (in_bom yes) (on_board yes) (dnp no)
    (property "Reference" "R100" (at 374.65 327.66 0)
      (effects (font (size 1.27 1.27)) (justify right))
    )
    (property "Value" "R_10k_0402" (at 378.46 322.58 0)
      (effects (font (size 1.524 1.524)) hide)
    )
    (property "Footprint" "sdi-mipi-bridge-footprints:R_0402_1005Metric" (at 369.57 317.5 0)
      (effects (font (size 1.524 1.524)) (justify left) hide)
    )
    (property "Datasheet" "https://www.bourns.com/docs/product-datasheets/cr.pdf" (at 374.65 322.58 0)
      (effects (font (size 1.27 1.27)) hide)
    )
    (property "Manufacturer" "Bourns" (at 364.49 317.5 0)
      (effects (font (size 1.524 1.524)) (justify left) hide)
    )
    (property "MPN" "CR0402-FX-1002GLF" (at 367.03 317.5 0)
      (effects (font (size 1.524 1.524)) (justify left) hide)
    )
    (property "Val" "10k" (at 373.38 322.58 0)
      (effects (font (size 1.27 1.27)) (justify right))
    )
    (property "License" "Apache-2.0" (at 400.05 302.26 0)
      (effects (font (size 1.27 1.27) (thickness 0.15)) (justify left bottom) hide)
    )
    (property "Author" "Antmicro" (at 402.59 302.26 0)
      (effects (font (size 1.27 1.27) (thickness 0.15)) (justify left bottom) hide)
    )
    (property "Tolerance" "1%" (at 384.81 302.26 0)
      (effects (font (size 1.27 1.27)) (justify left bottom) hide)
    )
    (pin "1")
    (pin "2")
    (instances
      (project "sdi-mipi-bridge"
        (path ""
          (reference "R100") (unit 1)
        )
      )
    )
  )

  (symbol (lib_id "sdi-mipi-bridge:GNDA") (at 83.82 337.82 0) (unit 1)
    (in_bom yes) (on_board yes) (dnp no)
    (property "Reference" "#PWR0136" (at 83.82 344.17 0)
      (effects (font (size 1.27 1.27)) hide)
    )
    (property "Value" "GNDA" (at 83.947 342.2142 0)
      (effects (font (size 1.27 1.27)))
    )
    (property "Footprint" "" (at 83.82 337.82 0)
      (effects (font (size 1.27 1.27)) hide)
    )
    (property "Datasheet" "" (at 83.82 337.82 0)
      (effects (font (size 1.27 1.27)) hide)
    )
    (pin "1")
    (instances
      (project "sdi-mipi-bridge"
        (path ""
          (reference "#PWR0136") (unit 1)
        )
      )
    )
  )

  (symbol (lib_id "sdi-mipi-bridge:R_10k_0402") (at 345.44 299.72 90) (unit 1)
    (in_bom yes) (on_board yes) (dnp no)
    (property "Reference" "R83" (at 345.44 288.29 0)
      (effects (font (size 1.27 1.27)) (justify right))
    )
    (property "Value" "R_10k_0402" (at 349.25 299.72 0)
      (effects (font (size 1.524 1.524)) hide)
    )
    (property "Footprint" "sdi-mipi-bridge-footprints:R_0402_1005Metric" (at 340.36 294.64 0)
      (effects (font (size 1.524 1.524)) (justify left) hide)
    )
    (property "Datasheet" "https://www.bourns.com/docs/product-datasheets/cr.pdf" (at 345.44 299.72 0)
      (effects (font (size 1.27 1.27)) hide)
    )
    (property "Manufacturer" "Bourns" (at 335.28 294.64 0)
      (effects (font (size 1.524 1.524)) (justify left) hide)
    )
    (property "MPN" "CR0402-FX-1002GLF" (at 337.82 294.64 0)
      (effects (font (size 1.524 1.524)) (justify left) hide)
    )
    (property "Val" "10k" (at 344.17 299.72 0)
      (effects (font (size 1.27 1.27)) (justify right))
    )
    (property "DNP" "" (at 345.44 297.18 0)
      (effects (font (size 1.27 1.27)))
    )
    (property "License" "Apache-2.0" (at 370.84 279.4 0)
      (effects (font (size 1.27 1.27) (thickness 0.15)) (justify left bottom) hide)
    )
    (property "Author" "Antmicro" (at 373.38 279.4 0)
      (effects (font (size 1.27 1.27) (thickness 0.15)) (justify left bottom) hide)
    )
    (property "Tolerance" "1%" (at 355.6 279.4 0)
      (effects (font (size 1.27 1.27)) (justify left bottom) hide)
    )
    (pin "1")
    (pin "2")
    (instances
      (project "sdi-mipi-bridge"
        (path ""
          (reference "R83") (unit 1)
        )
      )
    )
  )

  (symbol (lib_id "sdi-mipi-bridge:GNDREF") (at 144.78 311.15 0) (unit 1)
    (in_bom yes) (on_board yes) (dnp no)
    (property "Reference" "#PWR0115" (at 144.78 317.5 0)
      (effects (font (size 1.27 1.27)) hide)
    )
    (property "Value" "GNDREF" (at 144.78 314.96 0)
      (effects (font (size 1.27 1.27)))
    )
    (property "Footprint" "" (at 144.78 311.15 0)
      (effects (font (size 1.27 1.27)) hide)
    )
    (property "Datasheet" "" (at 144.78 311.15 0)
      (effects (font (size 1.27 1.27)) hide)
    )
    (pin "1")
    (instances
      (project "sdi-mipi-bridge"
        (path ""
          (reference "#PWR0115") (unit 1)
        )
      )
    )
  )

  (symbol (lib_id "sdi-mipi-bridge:GS2971A") (at 283.21 58.42 0) (unit 3)
    (in_bom yes) (on_board yes) (dnp no) (fields_autoplaced)
    (property "Reference" "U2" (at 296.545 50.165 0)
      (effects (font (size 1.27 1.27) (thickness 0.15)))
    )
    (property "Value" "GS2971A" (at 296.545 52.705 0)
      (effects (font (size 1.27 1.27) (thickness 0.15)))
    )
    (property "Footprint" "sdi-mipi-bridge-footprints:BGA100_11x11mm_SEMTECH" (at 339.09 66.04 0)
      (effects (font (size 1.27 1.27) (thickness 0.15)) (justify left bottom) hide)
    )
    (property "Datasheet" "https://semtech.my.salesforce.com/sfc/p/#E0000000JelG/a/44000000MD3i/kpmMkrmUWgHlbCOwdLzVohMm1SDPoVH85guEGK.KXTc" (at 339.09 68.58 0)
      (effects (font (size 1.27 1.27) (thickness 0.15)) (justify left bottom) hide)
    )
    (property "MPN" "GS2971A" (at 339.09 71.12 0)
      (effects (font (size 1.27 1.27) (thickness 0.15)) (justify left bottom) hide)
    )
    (property "Manufacturer" "Semtech" (at 339.09 73.66 0)
      (effects (font (size 1.27 1.27) (thickness 0.15)) (justify left bottom) hide)
    )
    (property "Author" "Antmicro" (at 339.09 76.2 0)
      (effects (font (size 1.27 1.27) (thickness 0.15)) (justify left bottom) hide)
    )
    (property "License" "Apache-2.0" (at 339.09 78.74 0)
      (effects (font (size 1.27 1.27) (thickness 0.15)) (justify left bottom) hide)
    )
    (pin "A10")
    (pin "A5")
    (pin "A6")
    (pin "A8")
    (pin "A9")
    (pin "B10")
    (pin "B5")
    (pin "B6")
    (pin "B8")
    (pin "B9")
    (pin "C10")
    (pin "C5")
    (pin "C6")
    (pin "C8")
    (pin "C9")
    (pin "E10")
    (pin "E9")
    (pin "F10")
    (pin "F9")
    (pin "H10")
    (pin "H4")
    (pin "H9")
    (pin "J1")
    (pin "J10")
    (pin "J3")
    (pin "J4")
    (pin "J5")
    (pin "J8")
    (pin "J9")
    (pin "K1")
    (pin "K10")
    (pin "K3")
    (pin "K4")
    (pin "K5")
    (pin "K8")
    (pin "K9")
    (pin "A1")
    (pin "A2")
    (pin "A3")
    (pin "B3")
    (pin "C1")
    (pin "C7")
    (pin "D1")
    (pin "D7")
    (pin "D8")
    (pin "E7")
    (pin "E8")
    (pin "F1")
    (pin "F2")
    (pin "F7")
    (pin "F8")
    (pin "G1")
    (pin "G3")
    (pin "G7")
    (pin "G8")
    (pin "H3")
    (pin "H5")
    (pin "H6")
    (pin "H7")
    (pin "H8")
    (pin "J2")
    (pin "J6")
    (pin "K2")
    (pin "K6")
    (pin "A4")
    (pin "A7")
    (pin "B1")
    (pin "B2")
    (pin "B4")
    (pin "B7")
    (pin "C2")
    (pin "C3")
    (pin "C4")
    (pin "D10")
    (pin "D2")
    (pin "D3")
    (pin "D4")
    (pin "D5")
    (pin "D6")
    (pin "D9")
    (pin "E1")
    (pin "E2")
    (pin "E3")
    (pin "E4")
    (pin "E5")
    (pin "E6")
    (pin "F3")
    (pin "F4")
    (pin "F5")
    (pin "F6")
    (pin "G10")
    (pin "G2")
    (pin "G4")
    (pin "G5")
    (pin "G6")
    (pin "G9")
    (pin "H1")
    (pin "H2")
    (pin "J7")
    (pin "K7")
    (instances
      (project "sdi-mipi-bridge"
        (path ""
          (reference "U2") (unit 3)
        )
      )
    )
  )

  (symbol (lib_id "sdi-mipi-bridge:R_10k_0402") (at 334.01 299.72 90) (unit 1)
    (in_bom yes) (on_board yes) (dnp no)
    (property "Reference" "R76" (at 334.01 288.29 0)
      (effects (font (size 1.27 1.27)) (justify right))
    )
    (property "Value" "R_10k_0402" (at 337.82 299.72 0)
      (effects (font (size 1.524 1.524)) hide)
    )
    (property "Footprint" "sdi-mipi-bridge-footprints:R_0402_1005Metric" (at 328.93 294.64 0)
      (effects (font (size 1.524 1.524)) (justify left) hide)
    )
    (property "Datasheet" "https://www.bourns.com/docs/product-datasheets/cr.pdf" (at 334.01 299.72 0)
      (effects (font (size 1.27 1.27)) hide)
    )
    (property "Manufacturer" "Bourns" (at 323.85 294.64 0)
      (effects (font (size 1.524 1.524)) (justify left) hide)
    )
    (property "MPN" "CR0402-FX-1002GLF" (at 326.39 294.64 0)
      (effects (font (size 1.524 1.524)) (justify left) hide)
    )
    (property "Val" "10k" (at 332.74 299.72 0)
      (effects (font (size 1.27 1.27)) (justify right))
    )
    (property "License" "Apache-2.0" (at 359.41 279.4 0)
      (effects (font (size 1.27 1.27) (thickness 0.15)) (justify left bottom) hide)
    )
    (property "Author" "Antmicro" (at 361.95 279.4 0)
      (effects (font (size 1.27 1.27) (thickness 0.15)) (justify left bottom) hide)
    )
    (property "Tolerance" "1%" (at 344.17 279.4 0)
      (effects (font (size 1.27 1.27)) (justify left bottom) hide)
    )
    (pin "1")
    (pin "2")
    (instances
      (project "sdi-mipi-bridge"
        (path ""
          (reference "R76") (unit 1)
        )
      )
    )
  )

  (symbol (lib_id "sdi-mipi-bridge:R_0R_0402") (at 346.71 369.57 0) (unit 1)
    (in_bom yes) (on_board yes) (dnp no)
    (property "Reference" "R82" (at 349.25 367.03 0)
      (effects (font (size 1.27 1.27)))
    )
    (property "Value" "R_0R_0402" (at 346.71 373.38 0)
      (effects (font (size 1.524 1.524)) hide)
    )
    (property "Footprint" "sdi-mipi-bridge-footprints:R_0402_1005Metric" (at 351.79 364.49 0)
      (effects (font (size 1.524 1.524)) (justify left) hide)
    )
    (property "Datasheet" "https://industrial.panasonic.com/cdbs/www-data/pdf/RDA0000/AOA0000C301.pdf" (at 346.71 369.57 0)
      (effects (font (size 1.27 1.27)) hide)
    )
    (property "Manufacturer" "Panasonic" (at 351.79 359.41 0)
      (effects (font (size 1.524 1.524)) (justify left) hide)
    )
    (property "MPN" "ERJ2GE0R00X" (at 351.79 361.95 0)
      (effects (font (size 1.524 1.524)) (justify left) hide)
    )
    (property "Val" "0R" (at 349.25 372.11 0)
      (effects (font (size 1.27 1.27)))
    )
    (property "License" "Apache-2.0" (at 367.03 394.97 0)
      (effects (font (size 1.27 1.27) (thickness 0.15)) (justify left bottom) hide)
    )
    (property "Author" "Antmicro" (at 367.03 397.51 0)
      (effects (font (size 1.27 1.27) (thickness 0.15)) (justify left bottom) hide)
    )
    (property "Tolerance" "~" (at 367.03 379.73 0)
      (effects (font (size 1.27 1.27)) (justify left bottom) hide)
    )
    (property "Current" "1A" (at 367.03 400.05 0)
      (effects (font (size 1.27 1.27) (thickness 0.15)) (justify left bottom) hide)
    )
    (pin "1")
    (pin "2")
    (instances
      (project "sdi-mipi-bridge"
        (path ""
          (reference "R82") (unit 1)
        )
      )
    )
  )

  (symbol (lib_id "sdi-mipi-bridge:PinHeader_2x5_P1.27mm_Drill0.65mm") (at 532.13 100.33 0) (unit 1)
    (in_bom yes) (on_board yes) (dnp no) (fields_autoplaced)
    (property "Reference" "J4" (at 537.21 93.98 0)
      (effects (font (size 1.27 1.27) (thickness 0.15)))
    )
    (property "Value" "PinHeader_2x5_P1.27mm_Vertical" (at 557.53 110.49 0)
      (effects (font (size 1.27 1.27) (thickness 0.15)) (justify left bottom) hide)
    )
    (property "Footprint" "sdi-mipi-bridge-footprints:PinHeader_2x5_P1.27mm_Drill0.65mm" (at 557.53 113.03 0)
      (effects (font (size 1.27 1.27) (thickness 0.15)) (justify left bottom) hide)
    )
    (property "Datasheet" "https://www.farnell.com/datasheets/3108040.pdf" (at 557.53 115.57 0)
      (effects (font (size 1.27 1.27) (thickness 0.15)) (justify left bottom) hide)
    )
    (property "MPN" "2199SB-10G-301523" (at 537.21 96.52 0)
      (effects (font (size 1.27 1.27) (thickness 0.15)))
    )
    (property "Manufacturer" "Multicomp Pro" (at 557.53 118.11 0)
      (effects (font (size 1.27 1.27) (thickness 0.15)) (justify left bottom) hide)
    )
    (property "Author" "Antmicro" (at 557.53 120.65 0)
      (effects (font (size 1.27 1.27) (thickness 0.15)) (justify left bottom) hide)
    )
    (property "License" "Apache-2.0" (at 557.53 123.19 0)
      (effects (font (size 1.27 1.27) (thickness 0.15)) (justify left bottom) hide)
    )
    (pin "1")
    (pin "10")
    (pin "2")
    (pin "3")
    (pin "4")
    (pin "5")
    (pin "6")
    (pin "7")
    (pin "8")
    (pin "9")
    (instances
      (project "sdi-mipi-bridge"
        (path ""
          (reference "J4") (unit 1)
        )
      )
    )
  )

  (sheet_instances
    (path "/" (page "1"))
  )
)
